(kicad_sch
	(version 20250114)
	(generator "eeschema")
	(generator_version "9.0")
	(paper "A3")
	(title_block
		(title "SDI-MIPI Video Converter")
		(date "2023-10-12")
		(rev "1.1.4")
		(comment 1 "www.antmicro.com")
		(comment 2 "Antmicro Ltd.")
	)
	(junction
		(at 252.73 144.78)
		(diameter 0)
		(color 0 0 0 0)
	)
	(junction
		(at 128.27 210.82)
		(diameter 0)
		(color 0 0 0 0)
	)
	(junction
		(at 138.43 46.99)
		(diameter 0)
		(color 0 0 0 0)
	)
	(junction
		(at 176.53 259.08)
		(diameter 0)
		(color 0 0 0 0)
	)
	(junction
		(at 165.1 83.82)
		(diameter 0)
		(color 0 0 0 0)
	)
	(junction
		(at 165.1 120.65)
		(diameter 0)
		(color 0 0 0 0)
	)
	(junction
		(at 187.96 46.99)
		(diameter 0)
		(color 0 0 0 0)
	)
	(junction
		(at 165.1 166.37)
		(diameter 0)
		(color 0 0 0 0)
	)
	(junction
		(at 209.55 46.99)
		(diameter 0)
		(color 0 0 0 0)
	)
	(junction
		(at 252.73 138.43)
		(diameter 0)
		(color 0 0 0 0)
	)
	(junction
		(at 165.1 210.82)
		(diameter 0)
		(color 0 0 0 0)
	)
	(junction
		(at 165.1 259.08)
		(diameter 0)
		(color 0 0 0 0)
	)
	(junction
		(at 176.53 166.37)
		(diameter 0)
		(color 0 0 0 0)
	)
	(junction
		(at 128.27 46.99)
		(diameter 0)
		(color 0 0 0 0)
	)
	(junction
		(at 210.82 83.82)
		(diameter 0)
		(color 0 0 0 0)
	)
	(junction
		(at 252.73 116.84)
		(diameter 0)
		(color 0 0 0 0)
	)
	(junction
		(at 128.27 166.37)
		(diameter 0)
		(color 0 0 0 0)
	)
	(junction
		(at 252.73 124.46)
		(diameter 0)
		(color 0 0 0 0)
	)
	(junction
		(at 176.53 120.65)
		(diameter 0)
		(color 0 0 0 0)
	)
	(junction
		(at 128.27 83.82)
		(diameter 0)
		(color 0 0 0 0)
	)
	(junction
		(at 176.53 46.99)
		(diameter 0)
		(color 0 0 0 0)
	)
	(junction
		(at 252.73 129.54)
		(diameter 0)
		(color 0 0 0 0)
	)
	(junction
		(at 137.16 83.82)
		(diameter 0)
		(color 0 0 0 0)
	)
	(junction
		(at 176.53 210.82)
		(diameter 0)
		(color 0 0 0 0)
	)
	(junction
		(at 252.73 132.08)
		(diameter 0)
		(color 0 0 0 0)
	)
	(junction
		(at 252.73 151.13)
		(diameter 0)
		(color 0 0 0 0)
	)
	(junction
		(at 290.83 124.46)
		(diameter 0)
		(color 0 0 0 0)
	)
	(junction
		(at 176.53 83.82)
		(diameter 0)
		(color 0 0 0 0)
	)
	(junction
		(at 187.96 83.82)
		(diameter 0)
		(color 0 0 0 0)
	)
	(junction
		(at 290.83 120.65)
		(diameter 0)
		(color 0 0 0 0)
	)
	(junction
		(at 128.27 259.08)
		(diameter 0)
		(color 0 0 0 0)
	)
	(junction
		(at 128.27 120.65)
		(diameter 0)
		(color 0 0 0 0)
	)
	(junction
		(at 165.1 46.99)
		(diameter 0)
		(color 0 0 0 0)
	)
	(junction
		(at 199.39 83.82)
		(diameter 0)
		(color 0 0 0 0)
	)
	(no_connect
		(at 255.27 160.02)
	)
	(no_connect
		(at 255.27 157.48)
	)
	(no_connect
		(at 255.27 162.56)
	)
	(wire
		(pts
			(xy 176.53 128.27) (xy 176.53 129.54)
		)
		(stroke
			(width 0)
			(type default)
		)
	)
	(wire
		(pts
			(xy 165.1 55.88) (xy 165.1 57.15)
		)
		(stroke
			(width 0)
			(type default)
		)
	)
	(wire
		(pts
			(xy 290.83 124.46) (xy 290.83 127)
		)
		(stroke
			(width 0)
			(type default)
		)
	)
	(wire
		(pts
			(xy 176.53 120.65) (xy 222.25 120.65)
		)
		(stroke
			(width 0)
			(type default)
		)
	)
	(wire
		(pts
			(xy 176.53 166.37) (xy 176.53 168.91)
		)
		(stroke
			(width 0)
			(type default)
		)
	)
	(wire
		(pts
			(xy 128.27 120.65) (xy 128.27 123.19)
		)
		(stroke
			(width 0)
			(type default)
		)
	)
	(wire
		(pts
			(xy 176.53 218.44) (xy 176.53 219.71)
		)
		(stroke
			(width 0)
			(type default)
		)
	)
	(wire
		(pts
			(xy 209.55 46.99) (xy 209.55 50.8)
		)
		(stroke
			(width 0)
			(type default)
		)
	)
	(wire
		(pts
			(xy 128.27 72.39) (xy 128.27 73.66)
		)
		(stroke
			(width 0)
			(type default)
		)
	)
	(wire
		(pts
			(xy 199.39 91.44) (xy 199.39 92.71)
		)
		(stroke
			(width 0)
			(type default)
		)
	)
	(wire
		(pts
			(xy 252.73 116.84) (xy 255.27 116.84)
		)
		(stroke
			(width 0)
			(type default)
		)
	)
	(wire
		(pts
			(xy 128.27 161.29) (xy 128.27 166.37)
		)
		(stroke
			(width 0)
			(type default)
		)
	)
	(wire
		(pts
			(xy 165.1 83.82) (xy 165.1 86.36)
		)
		(stroke
			(width 0)
			(type default)
		)
	)
	(wire
		(pts
			(xy 252.73 138.43) (xy 252.73 140.97)
		)
		(stroke
			(width 0)
			(type default)
		)
	)
	(wire
		(pts
			(xy 137.16 91.44) (xy 137.16 92.71)
		)
		(stroke
			(width 0)
			(type default)
		)
	)
	(wire
		(pts
			(xy 290.83 116.84) (xy 290.83 120.65)
		)
		(stroke
			(width 0)
			(type default)
		)
	)
	(wire
		(pts
			(xy 128.27 115.57) (xy 128.27 120.65)
		)
		(stroke
			(width 0)
			(type default)
		)
	)
	(wire
		(pts
			(xy 252.73 134.62) (xy 252.73 132.08)
		)
		(stroke
			(width 0)
			(type default)
		)
	)
	(wire
		(pts
			(xy 128.27 259.08) (xy 165.1 259.08)
		)
		(stroke
			(width 0)
			(type default)
		)
	)
	(wire
		(pts
			(xy 165.1 120.65) (xy 176.53 120.65)
		)
		(stroke
			(width 0)
			(type default)
		)
	)
	(wire
		(pts
			(xy 187.96 83.82) (xy 199.39 83.82)
		)
		(stroke
			(width 0)
			(type default)
		)
	)
	(wire
		(pts
			(xy 165.1 166.37) (xy 176.53 166.37)
		)
		(stroke
			(width 0)
			(type default)
		)
	)
	(wire
		(pts
			(xy 288.29 124.46) (xy 290.83 124.46)
		)
		(stroke
			(width 0)
			(type default)
		)
	)
	(wire
		(pts
			(xy 128.27 44.45) (xy 128.27 46.99)
		)
		(stroke
			(width 0)
			(type default)
		)
	)
	(wire
		(pts
			(xy 137.16 83.82) (xy 128.27 83.82)
		)
		(stroke
			(width 0)
			(type default)
		)
	)
	(wire
		(pts
			(xy 176.53 120.65) (xy 176.53 123.19)
		)
		(stroke
			(width 0)
			(type default)
		)
	)
	(wire
		(pts
			(xy 288.29 120.65) (xy 290.83 120.65)
		)
		(stroke
			(width 0)
			(type default)
		)
	)
	(wire
		(pts
			(xy 252.73 120.65) (xy 252.73 116.84)
		)
		(stroke
			(width 0)
			(type default)
		)
	)
	(wire
		(pts
			(xy 165.1 259.08) (xy 165.1 261.62)
		)
		(stroke
			(width 0)
			(type default)
		)
	)
	(wire
		(pts
			(xy 128.27 109.22) (xy 128.27 110.49)
		)
		(stroke
			(width 0)
			(type default)
		)
	)
	(wire
		(pts
			(xy 187.96 55.88) (xy 187.96 57.15)
		)
		(stroke
			(width 0)
			(type default)
		)
	)
	(wire
		(pts
			(xy 165.1 46.99) (xy 165.1 50.8)
		)
		(stroke
			(width 0)
			(type default)
		)
	)
	(wire
		(pts
			(xy 187.96 46.99) (xy 176.53 46.99)
		)
		(stroke
			(width 0)
			(type default)
		)
	)
	(wire
		(pts
			(xy 176.53 210.82) (xy 176.53 213.36)
		)
		(stroke
			(width 0)
			(type default)
		)
	)
	(wire
		(pts
			(xy 128.27 91.44) (xy 128.27 92.71)
		)
		(stroke
			(width 0)
			(type default)
		)
	)
	(wire
		(pts
			(xy 176.53 46.99) (xy 165.1 46.99)
		)
		(stroke
			(width 0)
			(type default)
		)
	)
	(wire
		(pts
			(xy 128.27 120.65) (xy 165.1 120.65)
		)
		(stroke
			(width 0)
			(type default)
		)
	)
	(wire
		(pts
			(xy 176.53 83.82) (xy 176.53 86.36)
		)
		(stroke
			(width 0)
			(type default)
		)
	)
	(wire
		(pts
			(xy 176.53 210.82) (xy 213.36 210.82)
		)
		(stroke
			(width 0)
			(type default)
		)
	)
	(wire
		(pts
			(xy 210.82 83.82) (xy 210.82 86.36)
		)
		(stroke
			(width 0)
			(type default)
		)
	)
	(wire
		(pts
			(xy 176.53 46.99) (xy 176.53 50.8)
		)
		(stroke
			(width 0)
			(type default)
		)
	)
	(wire
		(pts
			(xy 288.29 116.84) (xy 290.83 116.84)
		)
		(stroke
			(width 0)
			(type default)
		)
	)
	(wire
		(pts
			(xy 128.27 199.39) (xy 128.27 200.66)
		)
		(stroke
			(width 0)
			(type default)
		)
	)
	(wire
		(pts
			(xy 176.53 259.08) (xy 220.98 259.08)
		)
		(stroke
			(width 0)
			(type default)
		)
	)
	(wire
		(pts
			(xy 128.27 78.74) (xy 128.27 83.82)
		)
		(stroke
			(width 0)
			(type default)
		)
	)
	(wire
		(pts
			(xy 213.36 144.78) (xy 252.73 144.78)
		)
		(stroke
			(width 0)
			(type default)
		)
	)
	(wire
		(pts
			(xy 199.39 83.82) (xy 199.39 86.36)
		)
		(stroke
			(width 0)
			(type default)
		)
	)
	(wire
		(pts
			(xy 128.27 46.99) (xy 128.27 49.53)
		)
		(stroke
			(width 0)
			(type default)
		)
	)
	(wire
		(pts
			(xy 252.73 147.32) (xy 255.27 147.32)
		)
		(stroke
			(width 0)
			(type default)
		)
	)
	(wire
		(pts
			(xy 252.73 144.78) (xy 252.73 147.32)
		)
		(stroke
			(width 0)
			(type default)
		)
	)
	(wire
		(pts
			(xy 128.27 218.44) (xy 128.27 219.71)
		)
		(stroke
			(width 0)
			(type default)
		)
	)
	(wire
		(pts
			(xy 209.55 55.88) (xy 209.55 57.15)
		)
		(stroke
			(width 0)
			(type default)
		)
	)
	(wire
		(pts
			(xy 205.74 166.37) (xy 205.74 138.43)
		)
		(stroke
			(width 0)
			(type default)
		)
	)
	(wire
		(pts
			(xy 176.53 91.44) (xy 176.53 92.71)
		)
		(stroke
			(width 0)
			(type default)
		)
	)
	(wire
		(pts
			(xy 187.96 46.99) (xy 209.55 46.99)
		)
		(stroke
			(width 0)
			(type default)
		)
	)
	(wire
		(pts
			(xy 165.1 83.82) (xy 176.53 83.82)
		)
		(stroke
			(width 0)
			(type default)
		)
	)
	(wire
		(pts
			(xy 252.73 129.54) (xy 252.73 132.08)
		)
		(stroke
			(width 0)
			(type default)
		)
	)
	(wire
		(pts
			(xy 165.1 266.7) (xy 165.1 267.97)
		)
		(stroke
			(width 0)
			(type default)
		)
	)
	(wire
		(pts
			(xy 205.74 138.43) (xy 252.73 138.43)
		)
		(stroke
			(width 0)
			(type default)
		)
	)
	(wire
		(pts
			(xy 128.27 166.37) (xy 128.27 168.91)
		)
		(stroke
			(width 0)
			(type default)
		)
	)
	(wire
		(pts
			(xy 128.27 210.82) (xy 165.1 210.82)
		)
		(stroke
			(width 0)
			(type default)
		)
	)
	(wire
		(pts
			(xy 128.27 205.74) (xy 128.27 210.82)
		)
		(stroke
			(width 0)
			(type default)
		)
	)
	(wire
		(pts
			(xy 137.16 83.82) (xy 165.1 83.82)
		)
		(stroke
			(width 0)
			(type default)
		)
	)
	(wire
		(pts
			(xy 252.73 124.46) (xy 252.73 129.54)
		)
		(stroke
			(width 0)
			(type default)
		)
	)
	(wire
		(pts
			(xy 138.43 46.99) (xy 138.43 49.53)
		)
		(stroke
			(width 0)
			(type default)
		)
	)
	(wire
		(pts
			(xy 128.27 252.73) (xy 128.27 259.08)
		)
		(stroke
			(width 0)
			(type default)
		)
	)
	(wire
		(pts
			(xy 165.1 91.44) (xy 165.1 92.71)
		)
		(stroke
			(width 0)
			(type default)
		)
	)
	(wire
		(pts
			(xy 290.83 120.65) (xy 290.83 124.46)
		)
		(stroke
			(width 0)
			(type default)
		)
	)
	(wire
		(pts
			(xy 187.96 46.99) (xy 187.96 50.8)
		)
		(stroke
			(width 0)
			(type default)
		)
	)
	(wire
		(pts
			(xy 224.79 83.82) (xy 210.82 83.82)
		)
		(stroke
			(width 0)
			(type default)
		)
	)
	(wire
		(pts
			(xy 209.55 46.99) (xy 247.65 46.99)
		)
		(stroke
			(width 0)
			(type default)
		)
	)
	(wire
		(pts
			(xy 165.1 218.44) (xy 165.1 219.71)
		)
		(stroke
			(width 0)
			(type default)
		)
	)
	(wire
		(pts
			(xy 128.27 266.7) (xy 128.27 267.97)
		)
		(stroke
			(width 0)
			(type default)
		)
	)
	(wire
		(pts
			(xy 165.1 128.27) (xy 165.1 129.54)
		)
		(stroke
			(width 0)
			(type default)
		)
	)
	(wire
		(pts
			(xy 176.53 173.99) (xy 176.53 175.26)
		)
		(stroke
			(width 0)
			(type default)
		)
	)
	(wire
		(pts
			(xy 252.73 151.13) (xy 252.73 153.67)
		)
		(stroke
			(width 0)
			(type default)
		)
	)
	(wire
		(pts
			(xy 247.65 46.99) (xy 247.65 116.84)
		)
		(stroke
			(width 0)
			(type default)
		)
	)
	(wire
		(pts
			(xy 176.53 83.82) (xy 187.96 83.82)
		)
		(stroke
			(width 0)
			(type default)
		)
	)
	(wire
		(pts
			(xy 252.73 132.08) (xy 255.27 132.08)
		)
		(stroke
			(width 0)
			(type default)
		)
	)
	(wire
		(pts
			(xy 252.73 129.54) (xy 255.27 129.54)
		)
		(stroke
			(width 0)
			(type default)
		)
	)
	(wire
		(pts
			(xy 176.53 259.08) (xy 176.53 261.62)
		)
		(stroke
			(width 0)
			(type default)
		)
	)
	(wire
		(pts
			(xy 222.25 120.65) (xy 222.25 127)
		)
		(stroke
			(width 0)
			(type default)
		)
	)
	(wire
		(pts
			(xy 128.27 173.99) (xy 128.27 175.26)
		)
		(stroke
			(width 0)
			(type default)
		)
	)
	(wire
		(pts
			(xy 210.82 91.44) (xy 210.82 92.71)
		)
		(stroke
			(width 0)
			(type default)
		)
	)
	(wire
		(pts
			(xy 176.53 210.82) (xy 165.1 210.82)
		)
		(stroke
			(width 0)
			(type default)
		)
	)
	(wire
		(pts
			(xy 128.27 46.99) (xy 138.43 46.99)
		)
		(stroke
			(width 0)
			(type default)
		)
	)
	(wire
		(pts
			(xy 187.96 83.82) (xy 187.96 86.36)
		)
		(stroke
			(width 0)
			(type default)
		)
	)
	(wire
		(pts
			(xy 138.43 54.61) (xy 138.43 55.88)
		)
		(stroke
			(width 0)
			(type default)
		)
	)
	(wire
		(pts
			(xy 176.53 266.7) (xy 176.53 267.97)
		)
		(stroke
			(width 0)
			(type default)
		)
	)
	(wire
		(pts
			(xy 165.1 173.99) (xy 165.1 175.26)
		)
		(stroke
			(width 0)
			(type default)
		)
	)
	(wire
		(pts
			(xy 187.96 91.44) (xy 187.96 92.71)
		)
		(stroke
			(width 0)
			(type default)
		)
	)
	(wire
		(pts
			(xy 247.65 116.84) (xy 252.73 116.84)
		)
		(stroke
			(width 0)
			(type default)
		)
	)
	(wire
		(pts
			(xy 252.73 124.46) (xy 255.27 124.46)
		)
		(stroke
			(width 0)
			(type default)
		)
	)
	(wire
		(pts
			(xy 128.27 54.61) (xy 128.27 55.88)
		)
		(stroke
			(width 0)
			(type default)
		)
	)
	(wire
		(pts
			(xy 252.73 153.67) (xy 255.27 153.67)
		)
		(stroke
			(width 0)
			(type default)
		)
	)
	(wire
		(pts
			(xy 165.1 166.37) (xy 165.1 168.91)
		)
		(stroke
			(width 0)
			(type default)
		)
	)
	(wire
		(pts
			(xy 255.27 144.78) (xy 252.73 144.78)
		)
		(stroke
			(width 0)
			(type default)
		)
	)
	(wire
		(pts
			(xy 220.98 259.08) (xy 220.98 151.13)
		)
		(stroke
			(width 0)
			(type default)
		)
	)
	(wire
		(pts
			(xy 165.1 259.08) (xy 176.53 259.08)
		)
		(stroke
			(width 0)
			(type default)
		)
	)
	(wire
		(pts
			(xy 138.43 46.99) (xy 165.1 46.99)
		)
		(stroke
			(width 0)
			(type default)
		)
	)
	(wire
		(pts
			(xy 252.73 134.62) (xy 255.27 134.62)
		)
		(stroke
			(width 0)
			(type default)
		)
	)
	(wire
		(pts
			(xy 213.36 210.82) (xy 213.36 144.78)
		)
		(stroke
			(width 0)
			(type default)
		)
	)
	(wire
		(pts
			(xy 128.27 210.82) (xy 128.27 213.36)
		)
		(stroke
			(width 0)
			(type default)
		)
	)
	(wire
		(pts
			(xy 199.39 83.82) (xy 210.82 83.82)
		)
		(stroke
			(width 0)
			(type default)
		)
	)
	(wire
		(pts
			(xy 252.73 124.46) (xy 224.79 124.46)
		)
		(stroke
			(width 0)
			(type default)
		)
	)
	(wire
		(pts
			(xy 128.27 259.08) (xy 128.27 261.62)
		)
		(stroke
			(width 0)
			(type default)
		)
	)
	(wire
		(pts
			(xy 128.27 83.82) (xy 128.27 86.36)
		)
		(stroke
			(width 0)
			(type default)
		)
	)
	(wire
		(pts
			(xy 137.16 83.82) (xy 137.16 86.36)
		)
		(stroke
			(width 0)
			(type default)
		)
	)
	(wire
		(pts
			(xy 252.73 138.43) (xy 255.27 138.43)
		)
		(stroke
			(width 0)
			(type default)
		)
	)
	(wire
		(pts
			(xy 255.27 140.97) (xy 252.73 140.97)
		)
		(stroke
			(width 0)
			(type default)
		)
	)
	(wire
		(pts
			(xy 128.27 154.94) (xy 128.27 156.21)
		)
		(stroke
			(width 0)
			(type default)
		)
	)
	(wire
		(pts
			(xy 176.53 55.88) (xy 176.53 57.15)
		)
		(stroke
			(width 0)
			(type default)
		)
	)
	(wire
		(pts
			(xy 220.98 151.13) (xy 252.73 151.13)
		)
		(stroke
			(width 0)
			(type default)
		)
	)
	(wire
		(pts
			(xy 176.53 166.37) (xy 205.74 166.37)
		)
		(stroke
			(width 0)
			(type default)
		)
	)
	(wire
		(pts
			(xy 128.27 246.38) (xy 128.27 247.65)
		)
		(stroke
			(width 0)
			(type default)
		)
	)
	(wire
		(pts
			(xy 224.79 124.46) (xy 224.79 83.82)
		)
		(stroke
			(width 0)
			(type default)
		)
	)
	(wire
		(pts
			(xy 165.1 210.82) (xy 165.1 213.36)
		)
		(stroke
			(width 0)
			(type default)
		)
	)
	(wire
		(pts
			(xy 255.27 120.65) (xy 252.73 120.65)
		)
		(stroke
			(width 0)
			(type default)
		)
	)
	(wire
		(pts
			(xy 165.1 120.65) (xy 165.1 123.19)
		)
		(stroke
			(width 0)
			(type default)
		)
	)
	(wire
		(pts
			(xy 255.27 151.13) (xy 252.73 151.13)
		)
		(stroke
			(width 0)
			(type default)
		)
	)
	(wire
		(pts
			(xy 128.27 166.37) (xy 165.1 166.37)
		)
		(stroke
			(width 0)
			(type default)
		)
	)
	(wire
		(pts
			(xy 222.25 127) (xy 255.27 127)
		)
		(stroke
			(width 0)
			(type default)
		)
	)
	(wire
		(pts
			(xy 128.27 128.27) (xy 128.27 129.54)
		)
		(stroke
			(width 0)
			(type default)
		)
	)
	(label "VCC_DPHY"
		(at 161.29 166.37 0)
		(effects
			(font
				(size 1.27 1.27)
			)
			(justify left bottom)
		)
	)
	(label "VCC_ADPHY"
		(at 161.29 210.82 0)
		(effects
			(font
				(size 1.27 1.27)
			)
			(justify left bottom)
		)
	)
	(label "VCC_AUX"
		(at 201.93 83.82 0)
		(effects
			(font
				(size 1.27 1.27)
			)
			(justify left bottom)
		)
	)
	(label "VCC_AUXA"
		(at 161.29 120.65 0)
		(effects
			(font
				(size 1.27 1.27)
			)
			(justify left bottom)
		)
	)
	(label "VCC_PLLDPHY"
		(at 161.29 259.08 0)
		(effects
			(font
				(size 1.27 1.27)
			)
			(justify left bottom)
		)
	)
	(global_label "1V0_Clean"
		(shape input)
		(at 128.27 246.38 90)
		(fields_autoplaced yes)
		(effects
			(font
				(size 1.27 1.27)
			)
			(justify left)
		)
		(property "Intersheetrefs" "${INTERSHEET_REFS}"
			(at 128.1906 234.1698 90)
			(effects
				(font
					(size 1.27 1.27)
				)
				(justify left)
				(hide yes)
			)
		)
	)
	(global_label "1V0_Clean"
		(shape input)
		(at 128.27 154.94 90)
		(fields_autoplaced yes)
		(effects
			(font
				(size 1.27 1.27)
			)
			(justify left)
		)
		(property "Intersheetrefs" "${INTERSHEET_REFS}"
			(at 128.1906 142.7298 90)
			(effects
				(font
					(size 1.27 1.27)
				)
				(justify left)
				(hide yes)
			)
		)
	)
	(global_label "1V0_Power"
		(shape input)
		(at 128.27 44.45 90)
		(fields_autoplaced yes)
		(effects
			(font
				(size 1.27 1.27)
			)
			(justify left)
		)
		(property "Intersheetrefs" "${INTERSHEET_REFS}"
			(at 128.1906 31.9374 90)
			(effects
				(font
					(size 1.27 1.27)
				)
				(justify left)
				(hide yes)
			)
		)
	)
	(symbol
		(lib_id "antmicroCapacitors0603:C_10u_0603")
		(at 128.27 54.61 90)
		(unit 1)
		(exclude_from_sim no)
		(in_bom yes)
		(on_board yes)
		(dnp no)
		(fields_autoplaced yes)
		(property "Reference" "C86"
			(at 125.73 50.7935 90)
			(effects
				(font
					(size 1.27 1.27)
					(thickness 0.15)
				)
				(justify left)
			)
		)
		(property "Value" "C_10u_0603"
			(at 138.43 34.29 0)
			(effects
				(font
					(size 1.27 1.27)
					(thickness 0.15)
				)
				(justify left bottom)
				(hide yes)
			)
		)
		(property "Footprint" "antmicro-footprints:C_0603_1608Metric"
			(at 140.97 34.29 0)
			(effects
				(font
					(size 1.27 1.27)
					(thickness 0.15)
				)
				(justify left bottom)
				(hide yes)
			)
		)
		(property "Datasheet" "https://www.murata.com/products/productdetail?partno=GRM188R61A106KE69%23"
			(at 143.51 34.29 0)
			(effects
				(font
					(size 1.27 1.27)
					(thickness 0.15)
				)
				(justify left bottom)
				(hide yes)
			)
		)
		(property "Description" "SMD Multilayer Ceramic Capacitor, 10 µF, 10 V, 0603 [1608 Metric], ± 10%, X5R, GRM Series"
			(at 128.27 54.61 0)
			(effects
				(font
					(size 1.27 1.27)
				)
				(hide yes)
			)
		)
		(property "Manufacturer" "Murata"
			(at 148.59 34.29 0)
			(effects
				(font
					(size 1.27 1.27)
					(thickness 0.15)
				)
				(justify left bottom)
				(hide yes)
			)
		)
		(property "MPN" "GRM188R61A106KE69D"
			(at 146.05 34.29 0)
			(effects
				(font
					(size 1.27 1.27)
					(thickness 0.15)
				)
				(justify left bottom)
				(hide yes)
			)
		)
		(property "Val" "10u"
			(at 125.73 53.3335 90)
			(effects
				(font
					(size 1.27 1.27)
					(thickness 0.15)
				)
				(justify left)
			)
		)
		(property "License" "Apache-2.0"
			(at 151.13 34.29 0)
			(effects
				(font
					(size 1.27 1.27)
					(thickness 0.15)
				)
				(justify left bottom)
				(hide yes)
			)
		)
		(property "Author" "Antmicro"
			(at 153.67 34.29 0)
			(effects
				(font
					(size 1.27 1.27)
					(thickness 0.15)
				)
				(justify left bottom)
				(hide yes)
			)
		)
		(property "Voltage" ""
			(at 156.21 34.29 0)
			(effects
				(font
					(size 1.27 1.27)
				)
				(justify left bottom)
				(hide yes)
			)
		)
		(property "Dielectric" "template_dielectric"
			(at 158.75 34.29 0)
			(effects
				(font
					(size 1.27 1.27)
				)
				(justify left bottom)
				(hide yes)
			)
		)
		(pin "1"
		)
		(pin "2"
		)
		(instances
			(project "sdi-mipi-video-converter"
				(path ""
					(reference "C86")
					(unit 1)
				)
			)
		)
	)
	(symbol
		(lib_id "antmicropower:GND")
		(at 165.1 175.26 0)
		(mirror y)
		(unit 1)
		(exclude_from_sim no)
		(in_bom yes)
		(on_board yes)
		(dnp no)
		(fields_autoplaced yes)
		(property "Reference" "#PWR0201"
			(at 156.21 177.8 0)
			(effects
				(font
					(size 1.27 1.27)
					(thickness 0.15)
				)
				(justify left bottom)
				(hide yes)
			)
		)
		(property "Value" "GND"
			(at 165.1 180.34 0)
			(effects
				(font
					(size 1.27 1.27)
					(thickness 0.15)
				)
			)
		)
		(property "Footprint" ""
			(at 156.21 182.88 0)
			(effects
				(font
					(size 1.27 1.27)
					(thickness 0.15)
				)
				(justify left bottom)
				(hide yes)
			)
		)
		(property "Datasheet" ""
			(at 156.21 187.96 0)
			(effects
				(font
					(size 1.27 1.27)
					(thickness 0.15)
				)
				(justify left bottom)
				(hide yes)
			)
		)
		(property "Description" ""
			(at 165.1 175.26 0)
			(effects
				(font
					(size 1.27 1.27)
				)
				(hide yes)
			)
		)
		(property "Author" "Antmicro"
			(at 156.21 182.88 0)
			(effects
				(font
					(size 1.27 1.27)
					(thickness 0.15)
				)
				(justify left bottom)
				(hide yes)
			)
		)
		(property "License" "Apache-2.0"
			(at 156.21 185.42 0)
			(effects
				(font
					(size 1.27 1.27)
					(thickness 0.15)
				)
				(justify left bottom)
				(hide yes)
			)
		)
		(pin "1"
		)
		(instances
			(project "sdi-mipi-video-converter"
				(path ""
					(reference "#PWR0201")
					(unit 1)
				)
			)
		)
	)
	(symbol
		(lib_id "antmicroFerriteBeadsandChips:FB_120Z_2A_Murata-BLM18PG_0603")
		(at 128.27 78.74 90)
		(unit 1)
		(exclude_from_sim no)
		(in_bom yes)
		(on_board yes)
		(dnp no)
		(fields_autoplaced yes)
		(property "Reference" "FB1"
			(at 130.81 74.968 90)
			(effects
				(font
					(size 1.27 1.27)
					(thickness 0.15)
				)
				(justify right)
			)
		)
		(property "Value" "FB_120Z_2A_0603"
			(at 133.35 63.5 0)
			(effects
				(font
					(size 1.27 1.27)
					(thickness 0.15)
				)
				(justify left bottom)
				(hide yes)
			)
		)
		(property "Footprint" "antmicro-footprints:FB_0603_1608Metric"
			(at 135.89 63.5 0)
			(effects
				(font
					(size 1.27 1.27)
					(thickness 0.15)
				)
				(justify left bottom)
				(hide yes)
			)
		)
		(property "Datasheet" "https://www.murata.com/en-us/products/productdata/8796738650142/ENFA0003.pdf"
			(at 138.43 63.5 0)
			(effects
				(font
					(size 1.27 1.27)
					(thickness 0.15)
				)
				(justify left bottom)
				(hide yes)
			)
		)
		(property "Description" "Ferrite Bead, 0603 [1608 Metric], 120 ohm, 2 A, BLM18P, 0.05 ohm, ± 25%, DC power line"
			(at 128.27 78.74 0)
			(effects
				(font
					(size 1.27 1.27)
				)
				(hide yes)
			)
		)
		(property "MPN" "BLM18PG121SN1D"
			(at 130.81 77.508 90)
			(effects
				(font
					(size 1.27 1.27)
					(thickness 0.15)
				)
				(justify right)
			)
		)
		(property "Manufacturer" "Murata"
			(at 143.51 63.5 0)
			(effects
				(font
					(size 1.27 1.27)
					(thickness 0.15)
				)
				(justify left bottom)
				(hide yes)
			)
		)
		(property "Author" "Antmicro"
			(at 146.05 63.5 0)
			(effects
				(font
					(size 1.27 1.27)
					(thickness 0.15)
				)
				(justify left bottom)
				(hide yes)
			)
		)
		(property "License" "Apache-2.0"
			(at 148.59 63.5 0)
			(effects
				(font
					(size 1.27 1.27)
					(thickness 0.15)
				)
				(justify left bottom)
				(hide yes)
			)
		)
		(property "Val" "120Z/2A"
			(at 133.35 63.5 0)
			(effects
				(font
					(size 1.27 1.27)
				)
				(justify left bottom)
			)
		)
		(property "Current" ""
			(at 151.13 58.42 0)
			(effects
				(font
					(size 1.27 1.27)
					(thickness 0.15)
				)
				(justify left bottom)
				(hide yes)
			)
		)
		(pin "1"
		)
		(pin "2"
		)
		(instances
			(project "sdi-mipi-video-converter"
				(path ""
					(reference "FB1")
					(unit 1)
				)
			)
		)
	)
	(symbol
		(lib_id "antmicropower:GND")
		(at 290.83 127 0)
		(unit 1)
		(exclude_from_sim no)
		(in_bom yes)
		(on_board yes)
		(dnp no)
		(fields_autoplaced yes)
		(property "Reference" "#PWR0214"
			(at 299.72 129.54 0)
			(effects
				(font
					(size 1.27 1.27)
					(thickness 0.15)
				)
				(justify left bottom)
				(hide yes)
			)
		)
		(property "Value" "GND"
			(at 290.83 132.08 0)
			(effects
				(font
					(size 1.27 1.27)
					(thickness 0.15)
				)
			)
		)
		(property "Footprint" ""
			(at 299.72 134.62 0)
			(effects
				(font
					(size 1.27 1.27)
					(thickness 0.15)
				)
				(justify left bottom)
				(hide yes)
			)
		)
		(property "Datasheet" ""
			(at 299.72 139.7 0)
			(effects
				(font
					(size 1.27 1.27)
					(thickness 0.15)
				)
				(justify left bottom)
				(hide yes)
			)
		)
		(property "Description" ""
			(at 290.83 127 0)
			(effects
				(font
					(size 1.27 1.27)
				)
				(hide yes)
			)
		)
		(property "Author" "Antmicro"
			(at 299.72 134.62 0)
			(effects
				(font
					(size 1.27 1.27)
					(thickness 0.15)
				)
				(justify left bottom)
				(hide yes)
			)
		)
		(property "License" "Apache-2.0"
			(at 299.72 137.16 0)
			(effects
				(font
					(size 1.27 1.27)
					(thickness 0.15)
				)
				(justify left bottom)
				(hide yes)
			)
		)
		(pin "1"
		)
		(instances
			(project "sdi-mipi-video-converter"
				(path ""
					(reference "#PWR0214")
					(unit 1)
				)
			)
		)
	)
	(symbol
		(lib_id "antmicroFerriteBeadsandChips:FB_120Z_2A_Murata-BLM18PG_0603")
		(at 128.27 115.57 90)
		(unit 1)
		(exclude_from_sim no)
		(in_bom yes)
		(on_board yes)
		(dnp no)
		(fields_autoplaced yes)
		(property "Reference" "FB2"
			(at 125.73 111.798 90)
			(effects
				(font
					(size 1.27 1.27)
					(thickness 0.15)
				)
				(justify left)
			)
		)
		(property "Value" "FB_120Z_2A_0603"
			(at 133.35 100.33 0)
			(effects
				(font
					(size 1.27 1.27)
					(thickness 0.15)
				)
				(justify left bottom)
				(hide yes)
			)
		)
		(property "Footprint" "antmicro-footprints:FB_0603_1608Metric"
			(at 135.89 100.33 0)
			(effects
				(font
					(size 1.27 1.27)
					(thickness 0.15)
				)
				(justify left bottom)
				(hide yes)
			)
		)
		(property "Datasheet" "https://www.murata.com/en-us/products/productdata/8796738650142/ENFA0003.pdf"
			(at 138.43 100.33 0)
			(effects
				(font
					(size 1.27 1.27)
					(thickness 0.15)
				)
				(justify left bottom)
				(hide yes)
			)
		)
		(property "Description" "Ferrite Bead, 0603 [1608 Metric], 120 ohm, 2 A, BLM18P, 0.05 ohm, ± 25%, DC power line"
			(at 128.27 115.57 0)
			(effects
				(font
					(size 1.27 1.27)
				)
				(hide yes)
			)
		)
		(property "MPN" "BLM18PG121SN1D"
			(at 125.73 114.338 90)
			(effects
				(font
					(size 1.27 1.27)
					(thickness 0.15)
				)
				(justify left)
			)
		)
		(property "Manufacturer" "Murata"
			(at 143.51 100.33 0)
			(effects
				(font
					(size 1.27 1.27)
					(thickness 0.15)
				)
				(justify left bottom)
				(hide yes)
			)
		)
		(property "Author" "Antmicro"
			(at 146.05 100.33 0)
			(effects
				(font
					(size 1.27 1.27)
					(thickness 0.15)
				)
				(justify left bottom)
				(hide yes)
			)
		)
		(property "License" "Apache-2.0"
			(at 148.59 100.33 0)
			(effects
				(font
					(size 1.27 1.27)
					(thickness 0.15)
				)
				(justify left bottom)
				(hide yes)
			)
		)
		(property "Val" "120Z/2A"
			(at 133.35 100.33 0)
			(effects
				(font
					(size 1.27 1.27)
				)
				(justify left bottom)
			)
		)
		(property "Current" ""
			(at 151.13 95.25 0)
			(effects
				(font
					(size 1.27 1.27)
					(thickness 0.15)
				)
				(justify left bottom)
				(hide yes)
			)
		)
		(pin "1"
		)
		(pin "2"
		)
		(instances
			(project "sdi-mipi-video-converter"
				(path ""
					(reference "FB2")
					(unit 1)
				)
			)
		)
	)
	(symbol
		(lib_id "antmicropower:GND")
		(at 176.53 175.26 0)
		(mirror y)
		(unit 1)
		(exclude_from_sim no)
		(in_bom yes)
		(on_board yes)
		(dnp no)
		(fields_autoplaced yes)
		(property "Reference" "#PWR0207"
			(at 167.64 177.8 0)
			(effects
				(font
					(size 1.27 1.27)
					(thickness 0.15)
				)
				(justify left bottom)
				(hide yes)
			)
		)
		(property "Value" "GND"
			(at 176.53 180.34 0)
			(effects
				(font
					(size 1.27 1.27)
					(thickness 0.15)
				)
			)
		)
		(property "Footprint" ""
			(at 167.64 182.88 0)
			(effects
				(font
					(size 1.27 1.27)
					(thickness 0.15)
				)
				(justify left bottom)
				(hide yes)
			)
		)
		(property "Datasheet" ""
			(at 167.64 187.96 0)
			(effects
				(font
					(size 1.27 1.27)
					(thickness 0.15)
				)
				(justify left bottom)
				(hide yes)
			)
		)
		(property "Description" ""
			(at 176.53 175.26 0)
			(effects
				(font
					(size 1.27 1.27)
				)
				(hide yes)
			)
		)
		(property "Author" "Antmicro"
			(at 167.64 182.88 0)
			(effects
				(font
					(size 1.27 1.27)
					(thickness 0.15)
				)
				(justify left bottom)
				(hide yes)
			)
		)
		(property "License" "Apache-2.0"
			(at 167.64 185.42 0)
			(effects
				(font
					(size 1.27 1.27)
					(thickness 0.15)
				)
				(justify left bottom)
				(hide yes)
			)
		)
		(pin "1"
		)
		(instances
			(project "sdi-mipi-video-converter"
				(path ""
					(reference "#PWR0207")
					(unit 1)
				)
			)
		)
	)
	(symbol
		(lib_id "antmicroCapacitorsmisc:C_100n_0201")
		(at 210.82 91.44 90)
		(unit 1)
		(exclude_from_sim no)
		(in_bom yes)
		(on_board yes)
		(dnp no)
		(fields_autoplaced yes)
		(property "Reference" "C118"
			(at 213.36 87.6235 90)
			(effects
				(font
					(size 1.27 1.27)
					(thickness 0.15)
				)
				(justify right)
			)
		)
		(property "Value" "C_100n_0201"
			(at 220.98 71.12 0)
			(effects
				(font
					(size 1.27 1.27)
					(thickness 0.15)
				)
				(justify left bottom)
				(hide yes)
			)
		)
		(property "Footprint" "antmicro-footprints:C_0201"
			(at 223.52 71.12 0)
			(effects
				(font
					(size 1.27 1.27)
					(thickness 0.15)
				)
				(justify left bottom)
				(hide yes)
			)
		)
		(property "Datasheet" "https://www.yageo.com/en/Chart/Download/pdf/CC0201KRX6S5BB104"
			(at 226.06 71.12 0)
			(effects
				(font
					(size 1.27 1.27)
					(thickness 0.15)
				)
				(justify left bottom)
				(hide yes)
			)
		)
		(property "Description" "SMD Multilayer Ceramic Capacitor, 0.1 µF, 6.3 V, 0201 [0603 Metric], ± 10%, X6S, CC Series"
			(at 210.82 91.44 0)
			(effects
				(font
					(size 1.27 1.27)
				)
				(hide yes)
			)
		)
		(property "Manufacturer" "YAGEO"
			(at 231.14 71.12 0)
			(effects
				(font
					(size 1.27 1.27)
					(thickness 0.15)
				)
				(justify left bottom)
				(hide yes)
			)
		)
		(property "MPN" "CC0201KRX6S5BB104"
			(at 228.6 71.12 0)
			(effects
				(font
					(size 1.27 1.27)
					(thickness 0.15)
				)
				(justify left bottom)
				(hide yes)
			)
		)
		(property "Val" "100n"
			(at 213.36 90.1635 90)
			(effects
				(font
					(size 1.27 1.27)
					(thickness 0.15)
				)
				(justify right)
			)
		)
		(property "License" "Apache-2.0"
			(at 233.68 71.12 0)
			(effects
				(font
					(size 1.27 1.27)
					(thickness 0.15)
				)
				(justify left bottom)
				(hide yes)
			)
		)
		(property "Author" "Antmicro"
			(at 236.22 71.12 0)
			(effects
				(font
					(size 1.27 1.27)
					(thickness 0.15)
				)
				(justify left bottom)
				(hide yes)
			)
		)
		(property "Voltage" ""
			(at 238.76 71.12 0)
			(effects
				(font
					(size 1.27 1.27)
				)
				(justify left bottom)
				(hide yes)
			)
		)
		(property "Dielectric" ""
			(at 241.3 71.12 0)
			(effects
				(font
					(size 1.27 1.27)
				)
				(justify left bottom)
				(hide yes)
			)
		)
		(property "Public" "False"
			(at 243.84 71.12 0)
			(effects
				(font
					(size 1.27 1.27)
				)
				(justify left bottom)
				(hide yes)
			)
		)
		(pin "1"
		)
		(pin "2"
		)
		(instances
			(project "sdi-mipi-video-converter"
				(path ""
					(reference "C118")
					(unit 1)
				)
			)
		)
	)
	(symbol
		(lib_id "antmicroFerriteBeadsandChips:FB_120Z_2A_Murata-BLM18PG_0603")
		(at 128.27 252.73 90)
		(unit 1)
		(exclude_from_sim no)
		(in_bom yes)
		(on_board yes)
		(dnp no)
		(fields_autoplaced yes)
		(property "Reference" "FB5"
			(at 130.81 248.958 90)
			(effects
				(font
					(size 1.27 1.27)
					(thickness 0.15)
				)
				(justify right)
			)
		)
		(property "Value" "FB_120Z_2A_0603"
			(at 133.35 237.49 0)
			(effects
				(font
					(size 1.27 1.27)
					(thickness 0.15)
				)
				(justify left bottom)
				(hide yes)
			)
		)
		(property "Footprint" "antmicro-footprints:FB_0603_1608Metric"
			(at 135.89 237.49 0)
			(effects
				(font
					(size 1.27 1.27)
					(thickness 0.15)
				)
				(justify left bottom)
				(hide yes)
			)
		)
		(property "Datasheet" "https://www.murata.com/en-us/products/productdata/8796738650142/ENFA0003.pdf"
			(at 138.43 237.49 0)
			(effects
				(font
					(size 1.27 1.27)
					(thickness 0.15)
				)
				(justify left bottom)
				(hide yes)
			)
		)
		(property "Description" "Ferrite Bead, 0603 [1608 Metric], 120 ohm, 2 A, BLM18P, 0.05 ohm, ± 25%, DC power line"
			(at 128.27 252.73 0)
			(effects
				(font
					(size 1.27 1.27)
				)
				(hide yes)
			)
		)
		(property "MPN" "BLM18PG121SN1D"
			(at 130.81 251.498 90)
			(effects
				(font
					(size 1.27 1.27)
					(thickness 0.15)
				)
				(justify right)
			)
		)
		(property "Manufacturer" "Murata"
			(at 143.51 237.49 0)
			(effects
				(font
					(size 1.27 1.27)
					(thickness 0.15)
				)
				(justify left bottom)
				(hide yes)
			)
		)
		(property "Author" "Antmicro"
			(at 146.05 237.49 0)
			(effects
				(font
					(size 1.27 1.27)
					(thickness 0.15)
				)
				(justify left bottom)
				(hide yes)
			)
		)
		(property "License" "Apache-2.0"
			(at 148.59 237.49 0)
			(effects
				(font
					(size 1.27 1.27)
					(thickness 0.15)
				)
				(justify left bottom)
				(hide yes)
			)
		)
		(property "Val" "120Z/2A"
			(at 133.35 237.49 0)
			(effects
				(font
					(size 1.27 1.27)
				)
				(justify left bottom)
			)
		)
		(property "Current" ""
			(at 151.13 232.41 0)
			(effects
				(font
					(size 1.27 1.27)
					(thickness 0.15)
				)
				(justify left bottom)
				(hide yes)
			)
		)
		(pin "1"
		)
		(pin "2"
		)
		(instances
			(project "sdi-mipi-video-converter"
				(path ""
					(reference "FB5")
					(unit 1)
				)
			)
		)
	)
	(symbol
		(lib_id "antmicropower:GND")
		(at 165.1 267.97 0)
		(mirror y)
		(unit 1)
		(exclude_from_sim no)
		(in_bom yes)
		(on_board yes)
		(dnp no)
		(property "Reference" "#PWR0203"
			(at 156.21 270.51 0)
			(effects
				(font
					(size 1.27 1.27)
					(thickness 0.15)
				)
				(justify left bottom)
				(hide yes)
			)
		)
		(property "Value" "GND"
			(at 167.005 272.415 0)
			(effects
				(font
					(size 1.27 1.27)
					(thickness 0.15)
				)
				(justify left)
			)
		)
		(property "Footprint" ""
			(at 156.21 275.59 0)
			(effects
				(font
					(size 1.27 1.27)
					(thickness 0.15)
				)
				(justify left bottom)
				(hide yes)
			)
		)
		(property "Datasheet" ""
			(at 156.21 280.67 0)
			(effects
				(font
					(size 1.27 1.27)
					(thickness 0.15)
				)
				(justify left bottom)
				(hide yes)
			)
		)
		(property "Description" ""
			(at 165.1 267.97 0)
			(effects
				(font
					(size 1.27 1.27)
				)
				(hide yes)
			)
		)
		(property "Author" "Antmicro"
			(at 156.21 275.59 0)
			(effects
				(font
					(size 1.27 1.27)
					(thickness 0.15)
				)
				(justify left bottom)
				(hide yes)
			)
		)
		(property "License" "Apache-2.0"
			(at 156.21 278.13 0)
			(effects
				(font
					(size 1.27 1.27)
					(thickness 0.15)
				)
				(justify left bottom)
				(hide yes)
			)
		)
		(pin "1"
		)
		(instances
			(project "sdi-mipi-video-converter"
				(path ""
					(reference "#PWR0203")
					(unit 1)
				)
			)
		)
	)
	(symbol
		(lib_id "antmicroCapacitorsmisc:C_100n_0201")
		(at 187.96 91.44 90)
		(unit 1)
		(exclude_from_sim no)
		(in_bom yes)
		(on_board yes)
		(dnp no)
		(fields_autoplaced yes)
		(property "Reference" "C105"
			(at 190.5 87.6235 90)
			(effects
				(font
					(size 1.27 1.27)
					(thickness 0.15)
				)
				(justify right)
			)
		)
		(property "Value" "C_100n_0201"
			(at 198.12 71.12 0)
			(effects
				(font
					(size 1.27 1.27)
					(thickness 0.15)
				)
				(justify left bottom)
				(hide yes)
			)
		)
		(property "Footprint" "antmicro-footprints:C_0201"
			(at 200.66 71.12 0)
			(effects
				(font
					(size 1.27 1.27)
					(thickness 0.15)
				)
				(justify left bottom)
				(hide yes)
			)
		)
		(property "Datasheet" "https://www.yageo.com/en/Chart/Download/pdf/CC0201KRX6S5BB104"
			(at 203.2 71.12 0)
			(effects
				(font
					(size 1.27 1.27)
					(thickness 0.15)
				)
				(justify left bottom)
				(hide yes)
			)
		)
		(property "Description" "SMD Multilayer Ceramic Capacitor, 0.1 µF, 6.3 V, 0201 [0603 Metric], ± 10%, X6S, CC Series"
			(at 187.96 91.44 0)
			(effects
				(font
					(size 1.27 1.27)
				)
				(hide yes)
			)
		)
		(property "Manufacturer" "YAGEO"
			(at 208.28 71.12 0)
			(effects
				(font
					(size 1.27 1.27)
					(thickness 0.15)
				)
				(justify left bottom)
				(hide yes)
			)
		)
		(property "MPN" "CC0201KRX6S5BB104"
			(at 205.74 71.12 0)
			(effects
				(font
					(size 1.27 1.27)
					(thickness 0.15)
				)
				(justify left bottom)
				(hide yes)
			)
		)
		(property "Val" "100n"
			(at 190.5 90.1635 90)
			(effects
				(font
					(size 1.27 1.27)
					(thickness 0.15)
				)
				(justify right)
			)
		)
		(property "License" "Apache-2.0"
			(at 210.82 71.12 0)
			(effects
				(font
					(size 1.27 1.27)
					(thickness 0.15)
				)
				(justify left bottom)
				(hide yes)
			)
		)
		(property "Author" "Antmicro"
			(at 213.36 71.12 0)
			(effects
				(font
					(size 1.27 1.27)
					(thickness 0.15)
				)
				(justify left bottom)
				(hide yes)
			)
		)
		(property "Voltage" ""
			(at 215.9 71.12 0)
			(effects
				(font
					(size 1.27 1.27)
				)
				(justify left bottom)
				(hide yes)
			)
		)
		(property "Dielectric" ""
			(at 218.44 71.12 0)
			(effects
				(font
					(size 1.27 1.27)
				)
				(justify left bottom)
				(hide yes)
			)
		)
		(property "Public" "False"
			(at 220.98 71.12 0)
			(effects
				(font
					(size 1.27 1.27)
				)
				(justify left bottom)
				(hide yes)
			)
		)
		(pin "1"
		)
		(pin "2"
		)
		(instances
			(project "sdi-mipi-video-converter"
				(path ""
					(reference "C105")
					(unit 1)
				)
			)
		)
	)
	(symbol
		(lib_id "antmicropower:GND")
		(at 165.1 92.71 0)
		(mirror y)
		(unit 1)
		(exclude_from_sim no)
		(in_bom yes)
		(on_board yes)
		(dnp no)
		(property "Reference" "#PWR0199"
			(at 156.21 95.25 0)
			(effects
				(font
					(size 1.27 1.27)
					(thickness 0.15)
				)
				(justify left bottom)
				(hide yes)
			)
		)
		(property "Value" "GND"
			(at 167.005 97.155 0)
			(effects
				(font
					(size 1.27 1.27)
					(thickness 0.15)
				)
				(justify left)
			)
		)
		(property "Footprint" ""
			(at 156.21 100.33 0)
			(effects
				(font
					(size 1.27 1.27)
					(thickness 0.15)
				)
				(justify left bottom)
				(hide yes)
			)
		)
		(property "Datasheet" ""
			(at 156.21 105.41 0)
			(effects
				(font
					(size 1.27 1.27)
					(thickness 0.15)
				)
				(justify left bottom)
				(hide yes)
			)
		)
		(property "Description" ""
			(at 165.1 92.71 0)
			(effects
				(font
					(size 1.27 1.27)
				)
				(hide yes)
			)
		)
		(property "Author" "Antmicro"
			(at 156.21 100.33 0)
			(effects
				(font
					(size 1.27 1.27)
					(thickness 0.15)
				)
				(justify left bottom)
				(hide yes)
			)
		)
		(property "License" "Apache-2.0"
			(at 156.21 102.87 0)
			(effects
				(font
					(size 1.27 1.27)
					(thickness 0.15)
				)
				(justify left bottom)
				(hide yes)
			)
		)
		(pin "1"
		)
		(instances
			(project "sdi-mipi-video-converter"
				(path ""
					(reference "#PWR0199")
					(unit 1)
				)
			)
		)
	)
	(symbol
		(lib_id "antmicropower:GND")
		(at 210.82 92.71 0)
		(mirror y)
		(unit 1)
		(exclude_from_sim no)
		(in_bom yes)
		(on_board yes)
		(dnp no)
		(fields_autoplaced yes)
		(property "Reference" "#PWR0213"
			(at 201.93 95.25 0)
			(effects
				(font
					(size 1.27 1.27)
					(thickness 0.15)
				)
				(justify left bottom)
				(hide yes)
			)
		)
		(property "Value" "GND"
			(at 210.82 97.79 0)
			(effects
				(font
					(size 1.27 1.27)
					(thickness 0.15)
				)
			)
		)
		(property "Footprint" ""
			(at 201.93 100.33 0)
			(effects
				(font
					(size 1.27 1.27)
					(thickness 0.15)
				)
				(justify left bottom)
				(hide yes)
			)
		)
		(property "Datasheet" ""
			(at 201.93 105.41 0)
			(effects
				(font
					(size 1.27 1.27)
					(thickness 0.15)
				)
				(justify left bottom)
				(hide yes)
			)
		)
		(property "Description" ""
			(at 210.82 92.71 0)
			(effects
				(font
					(size 1.27 1.27)
				)
				(hide yes)
			)
		)
		(property "Author" "Antmicro"
			(at 201.93 100.33 0)
			(effects
				(font
					(size 1.27 1.27)
					(thickness 0.15)
				)
				(justify left bottom)
				(hide yes)
			)
		)
		(property "License" "Apache-2.0"
			(at 201.93 102.87 0)
			(effects
				(font
					(size 1.27 1.27)
					(thickness 0.15)
				)
				(justify left bottom)
				(hide yes)
			)
		)
		(pin "1"
		)
		(instances
			(project "sdi-mipi-video-converter"
				(path ""
					(reference "#PWR0213")
					(unit 1)
				)
			)
		)
	)
	(symbol
		(lib_id "antmicropower:GND")
		(at 138.43 55.88 0)
		(mirror y)
		(unit 1)
		(exclude_from_sim no)
		(in_bom yes)
		(on_board yes)
		(dnp no)
		(property "Reference" "#PWR0185"
			(at 129.54 58.42 0)
			(effects
				(font
					(size 1.27 1.27)
					(thickness 0.15)
				)
				(justify left bottom)
				(hide yes)
			)
		)
		(property "Value" "GND"
			(at 140.335 60.325 0)
			(effects
				(font
					(size 1.27 1.27)
					(thickness 0.15)
				)
				(justify left)
			)
		)
		(property "Footprint" ""
			(at 129.54 63.5 0)
			(effects
				(font
					(size 1.27 1.27)
					(thickness 0.15)
				)
				(justify left bottom)
				(hide yes)
			)
		)
		(property "Datasheet" ""
			(at 129.54 68.58 0)
			(effects
				(font
					(size 1.27 1.27)
					(thickness 0.15)
				)
				(justify left bottom)
				(hide yes)
			)
		)
		(property "Description" ""
			(at 138.43 55.88 0)
			(effects
				(font
					(size 1.27 1.27)
				)
				(hide yes)
			)
		)
		(property "Author" "Antmicro"
			(at 129.54 63.5 0)
			(effects
				(font
					(size 1.27 1.27)
					(thickness 0.15)
				)
				(justify left bottom)
				(hide yes)
			)
		)
		(property "License" "Apache-2.0"
			(at 129.54 66.04 0)
			(effects
				(font
					(size 1.27 1.27)
					(thickness 0.15)
				)
				(justify left bottom)
				(hide yes)
			)
		)
		(pin "1"
		)
		(instances
			(project "sdi-mipi-video-converter"
				(path ""
					(reference "#PWR0185")
					(unit 1)
				)
			)
		)
	)
	(symbol
		(lib_id "antmicroCapacitorsmisc:C_100n_0201")
		(at 176.53 218.44 90)
		(unit 1)
		(exclude_from_sim no)
		(in_bom yes)
		(on_board yes)
		(dnp no)
		(fields_autoplaced yes)
		(property "Reference" "C102"
			(at 179.07 214.6235 90)
			(effects
				(font
					(size 1.27 1.27)
					(thickness 0.15)
				)
				(justify right)
			)
		)
		(property "Value" "C_100n_0201"
			(at 186.69 198.12 0)
			(effects
				(font
					(size 1.27 1.27)
					(thickness 0.15)
				)
				(justify left bottom)
				(hide yes)
			)
		)
		(property "Footprint" "antmicro-footprints:C_0201"
			(at 189.23 198.12 0)
			(effects
				(font
					(size 1.27 1.27)
					(thickness 0.15)
				)
				(justify left bottom)
				(hide yes)
			)
		)
		(property "Datasheet" "https://www.yageo.com/en/Chart/Download/pdf/CC0201KRX6S5BB104"
			(at 191.77 198.12 0)
			(effects
				(font
					(size 1.27 1.27)
					(thickness 0.15)
				)
				(justify left bottom)
				(hide yes)
			)
		)
		(property "Description" "SMD Multilayer Ceramic Capacitor, 0.1 µF, 6.3 V, 0201 [0603 Metric], ± 10%, X6S, CC Series"
			(at 176.53 218.44 0)
			(effects
				(font
					(size 1.27 1.27)
				)
				(hide yes)
			)
		)
		(property "Manufacturer" "YAGEO"
			(at 196.85 198.12 0)
			(effects
				(font
					(size 1.27 1.27)
					(thickness 0.15)
				)
				(justify left bottom)
				(hide yes)
			)
		)
		(property "MPN" "CC0201KRX6S5BB104"
			(at 194.31 198.12 0)
			(effects
				(font
					(size 1.27 1.27)
					(thickness 0.15)
				)
				(justify left bottom)
				(hide yes)
			)
		)
		(property "Val" "100n"
			(at 179.07 217.1635 90)
			(effects
				(font
					(size 1.27 1.27)
					(thickness 0.15)
				)
				(justify right)
			)
		)
		(property "License" "Apache-2.0"
			(at 199.39 198.12 0)
			(effects
				(font
					(size 1.27 1.27)
					(thickness 0.15)
				)
				(justify left bottom)
				(hide yes)
			)
		)
		(property "Author" "Antmicro"
			(at 201.93 198.12 0)
			(effects
				(font
					(size 1.27 1.27)
					(thickness 0.15)
				)
				(justify left bottom)
				(hide yes)
			)
		)
		(property "Voltage" ""
			(at 204.47 198.12 0)
			(effects
				(font
					(size 1.27 1.27)
				)
				(justify left bottom)
				(hide yes)
			)
		)
		(property "Dielectric" ""
			(at 207.01 198.12 0)
			(effects
				(font
					(size 1.27 1.27)
				)
				(justify left bottom)
				(hide yes)
			)
		)
		(property "Public" "False"
			(at 209.55 198.12 0)
			(effects
				(font
					(size 1.27 1.27)
				)
				(justify left bottom)
				(hide yes)
			)
		)
		(pin "1"
		)
		(pin "2"
		)
		(instances
			(project "sdi-mipi-video-converter"
				(path ""
					(reference "C102")
					(unit 1)
				)
			)
		)
	)
	(symbol
		(lib_id "antmicroCapacitorsmisc:C_100n_0201")
		(at 165.1 218.44 90)
		(unit 1)
		(exclude_from_sim no)
		(in_bom yes)
		(on_board yes)
		(dnp no)
		(fields_autoplaced yes)
		(property "Reference" "C96"
			(at 167.64 214.6235 90)
			(effects
				(font
					(size 1.27 1.27)
					(thickness 0.15)
				)
				(justify right)
			)
		)
		(property "Value" "C_100n_0201"
			(at 175.26 198.12 0)
			(effects
				(font
					(size 1.27 1.27)
					(thickness 0.15)
				)
				(justify left bottom)
				(hide yes)
			)
		)
		(property "Footprint" "antmicro-footprints:C_0201"
			(at 177.8 198.12 0)
			(effects
				(font
					(size 1.27 1.27)
					(thickness 0.15)
				)
				(justify left bottom)
				(hide yes)
			)
		)
		(property "Datasheet" "https://www.yageo.com/en/Chart/Download/pdf/CC0201KRX6S5BB104"
			(at 180.34 198.12 0)
			(effects
				(font
					(size 1.27 1.27)
					(thickness 0.15)
				)
				(justify left bottom)
				(hide yes)
			)
		)
		(property "Description" "SMD Multilayer Ceramic Capacitor, 0.1 µF, 6.3 V, 0201 [0603 Metric], ± 10%, X6S, CC Series"
			(at 165.1 218.44 0)
			(effects
				(font
					(size 1.27 1.27)
				)
				(hide yes)
			)
		)
		(property "Manufacturer" "YAGEO"
			(at 185.42 198.12 0)
			(effects
				(font
					(size 1.27 1.27)
					(thickness 0.15)
				)
				(justify left bottom)
				(hide yes)
			)
		)
		(property "MPN" "CC0201KRX6S5BB104"
			(at 182.88 198.12 0)
			(effects
				(font
					(size 1.27 1.27)
					(thickness 0.15)
				)
				(justify left bottom)
				(hide yes)
			)
		)
		(property "Val" "100n"
			(at 167.64 217.1635 90)
			(effects
				(font
					(size 1.27 1.27)
					(thickness 0.15)
				)
				(justify right)
			)
		)
		(property "License" "Apache-2.0"
			(at 187.96 198.12 0)
			(effects
				(font
					(size 1.27 1.27)
					(thickness 0.15)
				)
				(justify left bottom)
				(hide yes)
			)
		)
		(property "Author" "Antmicro"
			(at 190.5 198.12 0)
			(effects
				(font
					(size 1.27 1.27)
					(thickness 0.15)
				)
				(justify left bottom)
				(hide yes)
			)
		)
		(property "Voltage" ""
			(at 193.04 198.12 0)
			(effects
				(font
					(size 1.27 1.27)
				)
				(justify left bottom)
				(hide yes)
			)
		)
		(property "Dielectric" ""
			(at 195.58 198.12 0)
			(effects
				(font
					(size 1.27 1.27)
				)
				(justify left bottom)
				(hide yes)
			)
		)
		(property "Public" "False"
			(at 198.12 198.12 0)
			(effects
				(font
					(size 1.27 1.27)
				)
				(justify left bottom)
				(hide yes)
			)
		)
		(pin "1"
		)
		(pin "2"
		)
		(instances
			(project "sdi-mipi-video-converter"
				(path ""
					(reference "C96")
					(unit 1)
				)
			)
		)
	)
	(symbol
		(lib_id "antmicropower:GND")
		(at 165.1 57.15 0)
		(mirror y)
		(unit 1)
		(exclude_from_sim no)
		(in_bom yes)
		(on_board yes)
		(dnp no)
		(property "Reference" "#PWR0198"
			(at 156.21 59.69 0)
			(effects
				(font
					(size 1.27 1.27)
					(thickness 0.15)
				)
				(justify left bottom)
				(hide yes)
			)
		)
		(property "Value" "GND"
			(at 167.005 61.595 0)
			(effects
				(font
					(size 1.27 1.27)
					(thickness 0.15)
				)
				(justify left)
			)
		)
		(property "Footprint" ""
			(at 156.21 64.77 0)
			(effects
				(font
					(size 1.27 1.27)
					(thickness 0.15)
				)
				(justify left bottom)
				(hide yes)
			)
		)
		(property "Datasheet" ""
			(at 156.21 69.85 0)
			(effects
				(font
					(size 1.27 1.27)
					(thickness 0.15)
				)
				(justify left bottom)
				(hide yes)
			)
		)
		(property "Description" ""
			(at 165.1 57.15 0)
			(effects
				(font
					(size 1.27 1.27)
				)
				(hide yes)
			)
		)
		(property "Author" "Antmicro"
			(at 156.21 64.77 0)
			(effects
				(font
					(size 1.27 1.27)
					(thickness 0.15)
				)
				(justify left bottom)
				(hide yes)
			)
		)
		(property "License" "Apache-2.0"
			(at 156.21 67.31 0)
			(effects
				(font
					(size 1.27 1.27)
					(thickness 0.15)
				)
				(justify left bottom)
				(hide yes)
			)
		)
		(pin "1"
		)
		(instances
			(project "sdi-mipi-video-converter"
				(path ""
					(reference "#PWR0198")
					(unit 1)
				)
			)
		)
	)
	(symbol
		(lib_id "antmicropower:GND")
		(at 128.27 129.54 0)
		(mirror y)
		(unit 1)
		(exclude_from_sim no)
		(in_bom yes)
		(on_board yes)
		(dnp no)
		(fields_autoplaced yes)
		(property "Reference" "#PWR0191"
			(at 119.38 132.08 0)
			(effects
				(font
					(size 1.27 1.27)
					(thickness 0.15)
				)
				(justify left bottom)
				(hide yes)
			)
		)
		(property "Value" "GND"
			(at 128.27 134.62 0)
			(effects
				(font
					(size 1.27 1.27)
					(thickness 0.15)
				)
			)
		)
		(property "Footprint" ""
			(at 119.38 137.16 0)
			(effects
				(font
					(size 1.27 1.27)
					(thickness 0.15)
				)
				(justify left bottom)
				(hide yes)
			)
		)
		(property "Datasheet" ""
			(at 119.38 142.24 0)
			(effects
				(font
					(size 1.27 1.27)
					(thickness 0.15)
				)
				(justify left bottom)
				(hide yes)
			)
		)
		(property "Description" ""
			(at 128.27 129.54 0)
			(effects
				(font
					(size 1.27 1.27)
				)
				(hide yes)
			)
		)
		(property "Author" "Antmicro"
			(at 119.38 137.16 0)
			(effects
				(font
					(size 1.27 1.27)
					(thickness 0.15)
				)
				(justify left bottom)
				(hide yes)
			)
		)
		(property "License" "Apache-2.0"
			(at 119.38 139.7 0)
			(effects
				(font
					(size 1.27 1.27)
					(thickness 0.15)
				)
				(justify left bottom)
				(hide yes)
			)
		)
		(pin "1"
		)
		(instances
			(project "sdi-mipi-video-converter"
				(path ""
					(reference "#PWR0191")
					(unit 1)
				)
			)
		)
	)
	(symbol
		(lib_id "antmicropower:GND")
		(at 209.55 57.15 0)
		(mirror y)
		(unit 1)
		(exclude_from_sim no)
		(in_bom yes)
		(on_board yes)
		(dnp no)
		(property "Reference" "#PWR0260"
			(at 200.66 59.69 0)
			(effects
				(font
					(size 1.27 1.27)
					(thickness 0.15)
				)
				(justify left bottom)
				(hide yes)
			)
		)
		(property "Value" "GND"
			(at 209.55 61.595 0)
			(effects
				(font
					(size 1.27 1.27)
					(thickness 0.15)
				)
			)
		)
		(property "Footprint" ""
			(at 200.66 64.77 0)
			(effects
				(font
					(size 1.27 1.27)
					(thickness 0.15)
				)
				(justify left bottom)
				(hide yes)
			)
		)
		(property "Datasheet" ""
			(at 200.66 69.85 0)
			(effects
				(font
					(size 1.27 1.27)
					(thickness 0.15)
				)
				(justify left bottom)
				(hide yes)
			)
		)
		(property "Description" ""
			(at 209.55 57.15 0)
			(effects
				(font
					(size 1.27 1.27)
				)
				(hide yes)
			)
		)
		(property "Author" "Antmicro"
			(at 200.66 64.77 0)
			(effects
				(font
					(size 1.27 1.27)
					(thickness 0.15)
				)
				(justify left bottom)
				(hide yes)
			)
		)
		(property "License" "Apache-2.0"
			(at 200.66 67.31 0)
			(effects
				(font
					(size 1.27 1.27)
					(thickness 0.15)
				)
				(justify left bottom)
				(hide yes)
			)
		)
		(pin "1"
		)
		(instances
			(project "sdi-mipi-video-converter"
				(path ""
					(reference "#PWR0260")
					(unit 1)
				)
			)
		)
	)
	(symbol
		(lib_id "antmicropower:+1V8")
		(at 128.27 199.39 0)
		(unit 1)
		(exclude_from_sim no)
		(in_bom yes)
		(on_board yes)
		(dnp no)
		(fields_autoplaced yes)
		(property "Reference" "#PWR0193"
			(at 143.51 201.93 0)
			(effects
				(font
					(size 1.27 1.27)
					(thickness 0.15)
				)
				(justify left bottom)
				(hide yes)
			)
		)
		(property "Value" "+1V8"
			(at 128.27 194.31 0)
			(effects
				(font
					(size 1.27 1.27)
					(thickness 0.15)
				)
			)
		)
		(property "Footprint" ""
			(at 143.51 207.01 0)
			(effects
				(font
					(size 1.27 1.27)
					(thickness 0.15)
				)
				(justify left bottom)
				(hide yes)
			)
		)
		(property "Datasheet" ""
			(at 143.51 209.55 0)
			(effects
				(font
					(size 1.27 1.27)
					(thickness 0.15)
				)
				(justify left bottom)
				(hide yes)
			)
		)
		(property "Description" ""
			(at 128.27 199.39 0)
			(effects
				(font
					(size 1.27 1.27)
				)
				(hide yes)
			)
		)
		(property "Author" "Antmicro"
			(at 143.51 207.01 0)
			(effects
				(font
					(size 1.27 1.27)
					(thickness 0.15)
				)
				(justify left bottom)
				(hide yes)
			)
		)
		(property "License" "Apache-2.0"
			(at 143.51 209.55 0)
			(effects
				(font
					(size 1.27 1.27)
					(thickness 0.15)
				)
				(justify left bottom)
				(hide yes)
			)
		)
		(pin "1"
		)
		(instances
			(project "sdi-mipi-video-converter"
				(path ""
					(reference "#PWR0193")
					(unit 1)
				)
			)
		)
	)
	(symbol
		(lib_id "antmicropower:GND")
		(at 128.27 175.26 0)
		(mirror y)
		(unit 1)
		(exclude_from_sim no)
		(in_bom yes)
		(on_board yes)
		(dnp no)
		(fields_autoplaced yes)
		(property "Reference" "#PWR0192"
			(at 119.38 177.8 0)
			(effects
				(font
					(size 1.27 1.27)
					(thickness 0.15)
				)
				(justify left bottom)
				(hide yes)
			)
		)
		(property "Value" "GND"
			(at 128.27 180.34 0)
			(effects
				(font
					(size 1.27 1.27)
					(thickness 0.15)
				)
			)
		)
		(property "Footprint" ""
			(at 119.38 182.88 0)
			(effects
				(font
					(size 1.27 1.27)
					(thickness 0.15)
				)
				(justify left bottom)
				(hide yes)
			)
		)
		(property "Datasheet" ""
			(at 119.38 187.96 0)
			(effects
				(font
					(size 1.27 1.27)
					(thickness 0.15)
				)
				(justify left bottom)
				(hide yes)
			)
		)
		(property "Description" ""
			(at 128.27 175.26 0)
			(effects
				(font
					(size 1.27 1.27)
				)
				(hide yes)
			)
		)
		(property "Author" "Antmicro"
			(at 119.38 182.88 0)
			(effects
				(font
					(size 1.27 1.27)
					(thickness 0.15)
				)
				(justify left bottom)
				(hide yes)
			)
		)
		(property "License" "Apache-2.0"
			(at 119.38 185.42 0)
			(effects
				(font
					(size 1.27 1.27)
					(thickness 0.15)
				)
				(justify left bottom)
				(hide yes)
			)
		)
		(pin "1"
		)
		(instances
			(project "sdi-mipi-video-converter"
				(path ""
					(reference "#PWR0192")
					(unit 1)
				)
			)
		)
	)
	(symbol
		(lib_id "antmicropower:GND")
		(at 128.27 219.71 0)
		(mirror y)
		(unit 1)
		(exclude_from_sim no)
		(in_bom yes)
		(on_board yes)
		(dnp no)
		(fields_autoplaced yes)
		(property "Reference" "#PWR0194"
			(at 119.38 222.25 0)
			(effects
				(font
					(size 1.27 1.27)
					(thickness 0.15)
				)
				(justify left bottom)
				(hide yes)
			)
		)
		(property "Value" "GND"
			(at 128.27 224.79 0)
			(effects
				(font
					(size 1.27 1.27)
					(thickness 0.15)
				)
			)
		)
		(property "Footprint" ""
			(at 119.38 227.33 0)
			(effects
				(font
					(size 1.27 1.27)
					(thickness 0.15)
				)
				(justify left bottom)
				(hide yes)
			)
		)
		(property "Datasheet" ""
			(at 119.38 232.41 0)
			(effects
				(font
					(size 1.27 1.27)
					(thickness 0.15)
				)
				(justify left bottom)
				(hide yes)
			)
		)
		(property "Description" ""
			(at 128.27 219.71 0)
			(effects
				(font
					(size 1.27 1.27)
				)
				(hide yes)
			)
		)
		(property "Author" "Antmicro"
			(at 119.38 227.33 0)
			(effects
				(font
					(size 1.27 1.27)
					(thickness 0.15)
				)
				(justify left bottom)
				(hide yes)
			)
		)
		(property "License" "Apache-2.0"
			(at 119.38 229.87 0)
			(effects
				(font
					(size 1.27 1.27)
					(thickness 0.15)
				)
				(justify left bottom)
				(hide yes)
			)
		)
		(pin "1"
		)
		(instances
			(project "sdi-mipi-video-converter"
				(path ""
					(reference "#PWR0194")
					(unit 1)
				)
			)
		)
	)
	(symbol
		(lib_id "antmicroFerriteBeadsandChips:FB_120Z_2A_Murata-BLM18PG_0603")
		(at 128.27 161.29 90)
		(unit 1)
		(exclude_from_sim no)
		(in_bom yes)
		(on_board yes)
		(dnp no)
		(fields_autoplaced yes)
		(property "Reference" "FB3"
			(at 130.81 157.518 90)
			(effects
				(font
					(size 1.27 1.27)
					(thickness 0.15)
				)
				(justify right)
			)
		)
		(property "Value" "FB_120Z_2A_0603"
			(at 133.35 146.05 0)
			(effects
				(font
					(size 1.27 1.27)
					(thickness 0.15)
				)
				(justify left bottom)
				(hide yes)
			)
		)
		(property "Footprint" "antmicro-footprints:FB_0603_1608Metric"
			(at 135.89 146.05 0)
			(effects
				(font
					(size 1.27 1.27)
					(thickness 0.15)
				)
				(justify left bottom)
				(hide yes)
			)
		)
		(property "Datasheet" "https://www.murata.com/en-us/products/productdata/8796738650142/ENFA0003.pdf"
			(at 138.43 146.05 0)
			(effects
				(font
					(size 1.27 1.27)
					(thickness 0.15)
				)
				(justify left bottom)
				(hide yes)
			)
		)
		(property "Description" "Ferrite Bead, 0603 [1608 Metric], 120 ohm, 2 A, BLM18P, 0.05 ohm, ± 25%, DC power line"
			(at 128.27 161.29 0)
			(effects
				(font
					(size 1.27 1.27)
				)
				(hide yes)
			)
		)
		(property "MPN" "BLM18PG121SN1D"
			(at 130.81 160.058 90)
			(effects
				(font
					(size 1.27 1.27)
					(thickness 0.15)
				)
				(justify right)
			)
		)
		(property "Manufacturer" "Murata"
			(at 143.51 146.05 0)
			(effects
				(font
					(size 1.27 1.27)
					(thickness 0.15)
				)
				(justify left bottom)
				(hide yes)
			)
		)
		(property "Author" "Antmicro"
			(at 146.05 146.05 0)
			(effects
				(font
					(size 1.27 1.27)
					(thickness 0.15)
				)
				(justify left bottom)
				(hide yes)
			)
		)
		(property "License" "Apache-2.0"
			(at 148.59 146.05 0)
			(effects
				(font
					(size 1.27 1.27)
					(thickness 0.15)
				)
				(justify left bottom)
				(hide yes)
			)
		)
		(property "Val" "120Z/2A"
			(at 133.35 146.05 0)
			(effects
				(font
					(size 1.27 1.27)
				)
				(justify left bottom)
			)
		)
		(property "Current" ""
			(at 151.13 140.97 0)
			(effects
				(font
					(size 1.27 1.27)
					(thickness 0.15)
				)
				(justify left bottom)
				(hide yes)
			)
		)
		(pin "1"
		)
		(pin "2"
		)
		(instances
			(project "sdi-mipi-video-converter"
				(path ""
					(reference "FB3")
					(unit 1)
				)
			)
		)
	)
	(symbol
		(lib_id "antmicroCapacitorsmisc:C_100n_0201")
		(at 176.53 128.27 90)
		(unit 1)
		(exclude_from_sim no)
		(in_bom yes)
		(on_board yes)
		(dnp no)
		(fields_autoplaced yes)
		(property "Reference" "C100"
			(at 179.07 124.4535 90)
			(effects
				(font
					(size 1.27 1.27)
					(thickness 0.15)
				)
				(justify right)
			)
		)
		(property "Value" "C_100n_0201"
			(at 186.69 107.95 0)
			(effects
				(font
					(size 1.27 1.27)
					(thickness 0.15)
				)
				(justify left bottom)
				(hide yes)
			)
		)
		(property "Footprint" "antmicro-footprints:C_0201"
			(at 189.23 107.95 0)
			(effects
				(font
					(size 1.27 1.27)
					(thickness 0.15)
				)
				(justify left bottom)
				(hide yes)
			)
		)
		(property "Datasheet" "https://www.yageo.com/en/Chart/Download/pdf/CC0201KRX6S5BB104"
			(at 191.77 107.95 0)
			(effects
				(font
					(size 1.27 1.27)
					(thickness 0.15)
				)
				(justify left bottom)
				(hide yes)
			)
		)
		(property "Description" "SMD Multilayer Ceramic Capacitor, 0.1 µF, 6.3 V, 0201 [0603 Metric], ± 10%, X6S, CC Series"
			(at 176.53 128.27 0)
			(effects
				(font
					(size 1.27 1.27)
				)
				(hide yes)
			)
		)
		(property "Manufacturer" "YAGEO"
			(at 196.85 107.95 0)
			(effects
				(font
					(size 1.27 1.27)
					(thickness 0.15)
				)
				(justify left bottom)
				(hide yes)
			)
		)
		(property "MPN" "CC0201KRX6S5BB104"
			(at 194.31 107.95 0)
			(effects
				(font
					(size 1.27 1.27)
					(thickness 0.15)
				)
				(justify left bottom)
				(hide yes)
			)
		)
		(property "Val" "100n"
			(at 179.07 126.9935 90)
			(effects
				(font
					(size 1.27 1.27)
					(thickness 0.15)
				)
				(justify right)
			)
		)
		(property "License" "Apache-2.0"
			(at 199.39 107.95 0)
			(effects
				(font
					(size 1.27 1.27)
					(thickness 0.15)
				)
				(justify left bottom)
				(hide yes)
			)
		)
		(property "Author" "Antmicro"
			(at 201.93 107.95 0)
			(effects
				(font
					(size 1.27 1.27)
					(thickness 0.15)
				)
				(justify left bottom)
				(hide yes)
			)
		)
		(property "Voltage" ""
			(at 204.47 107.95 0)
			(effects
				(font
					(size 1.27 1.27)
				)
				(justify left bottom)
				(hide yes)
			)
		)
		(property "Dielectric" ""
			(at 207.01 107.95 0)
			(effects
				(font
					(size 1.27 1.27)
				)
				(justify left bottom)
				(hide yes)
			)
		)
		(property "Public" "False"
			(at 209.55 107.95 0)
			(effects
				(font
					(size 1.27 1.27)
				)
				(justify left bottom)
				(hide yes)
			)
		)
		(pin "1"
		)
		(pin "2"
		)
		(instances
			(project "sdi-mipi-video-converter"
				(path ""
					(reference "C100")
					(unit 1)
				)
			)
		)
	)
	(symbol
		(lib_id "antmicroCapacitorsmisc:C_100n_0201")
		(at 187.96 55.88 90)
		(unit 1)
		(exclude_from_sim no)
		(in_bom yes)
		(on_board yes)
		(dnp no)
		(fields_autoplaced yes)
		(property "Reference" "C104"
			(at 190.5 52.0635 90)
			(effects
				(font
					(size 1.27 1.27)
					(thickness 0.15)
				)
				(justify right)
			)
		)
		(property "Value" "C_100n_0201"
			(at 198.12 35.56 0)
			(effects
				(font
					(size 1.27 1.27)
					(thickness 0.15)
				)
				(justify left bottom)
				(hide yes)
			)
		)
		(property "Footprint" "antmicro-footprints:C_0201"
			(at 200.66 35.56 0)
			(effects
				(font
					(size 1.27 1.27)
					(thickness 0.15)
				)
				(justify left bottom)
				(hide yes)
			)
		)
		(property "Datasheet" "https://www.yageo.com/en/Chart/Download/pdf/CC0201KRX6S5BB104"
			(at 203.2 35.56 0)
			(effects
				(font
					(size 1.27 1.27)
					(thickness 0.15)
				)
				(justify left bottom)
				(hide yes)
			)
		)
		(property "Description" "SMD Multilayer Ceramic Capacitor, 0.1 µF, 6.3 V, 0201 [0603 Metric], ± 10%, X6S, CC Series"
			(at 187.96 55.88 0)
			(effects
				(font
					(size 1.27 1.27)
				)
				(hide yes)
			)
		)
		(property "Manufacturer" "YAGEO"
			(at 208.28 35.56 0)
			(effects
				(font
					(size 1.27 1.27)
					(thickness 0.15)
				)
				(justify left bottom)
				(hide yes)
			)
		)
		(property "MPN" "CC0201KRX6S5BB104"
			(at 205.74 35.56 0)
			(effects
				(font
					(size 1.27 1.27)
					(thickness 0.15)
				)
				(justify left bottom)
				(hide yes)
			)
		)
		(property "Val" "100n"
			(at 190.5 54.6035 90)
			(effects
				(font
					(size 1.27 1.27)
					(thickness 0.15)
				)
				(justify right)
			)
		)
		(property "License" "Apache-2.0"
			(at 210.82 35.56 0)
			(effects
				(font
					(size 1.27 1.27)
					(thickness 0.15)
				)
				(justify left bottom)
				(hide yes)
			)
		)
		(property "Author" "Antmicro"
			(at 213.36 35.56 0)
			(effects
				(font
					(size 1.27 1.27)
					(thickness 0.15)
				)
				(justify left bottom)
				(hide yes)
			)
		)
		(property "Voltage" ""
			(at 215.9 35.56 0)
			(effects
				(font
					(size 1.27 1.27)
				)
				(justify left bottom)
				(hide yes)
			)
		)
		(property "Dielectric" ""
			(at 218.44 35.56 0)
			(effects
				(font
					(size 1.27 1.27)
				)
				(justify left bottom)
				(hide yes)
			)
		)
		(property "Public" "False"
			(at 220.98 35.56 0)
			(effects
				(font
					(size 1.27 1.27)
				)
				(justify left bottom)
				(hide yes)
			)
		)
		(pin "1"
		)
		(pin "2"
		)
		(instances
			(project "sdi-mipi-video-converter"
				(path ""
					(reference "C104")
					(unit 1)
				)
			)
		)
	)
	(symbol
		(lib_id "antmicropower:GND")
		(at 165.1 219.71 0)
		(mirror y)
		(unit 1)
		(exclude_from_sim no)
		(in_bom yes)
		(on_board yes)
		(dnp no)
		(property "Reference" "#PWR0202"
			(at 156.21 222.25 0)
			(effects
				(font
					(size 1.27 1.27)
					(thickness 0.15)
				)
				(justify left bottom)
				(hide yes)
			)
		)
		(property "Value" "GND"
			(at 167.005 224.155 0)
			(effects
				(font
					(size 1.27 1.27)
					(thickness 0.15)
				)
				(justify left)
			)
		)
		(property "Footprint" ""
			(at 156.21 227.33 0)
			(effects
				(font
					(size 1.27 1.27)
					(thickness 0.15)
				)
				(justify left bottom)
				(hide yes)
			)
		)
		(property "Datasheet" ""
			(at 156.21 232.41 0)
			(effects
				(font
					(size 1.27 1.27)
					(thickness 0.15)
				)
				(justify left bottom)
				(hide yes)
			)
		)
		(property "Description" ""
			(at 165.1 219.71 0)
			(effects
				(font
					(size 1.27 1.27)
				)
				(hide yes)
			)
		)
		(property "Author" "Antmicro"
			(at 156.21 227.33 0)
			(effects
				(font
					(size 1.27 1.27)
					(thickness 0.15)
				)
				(justify left bottom)
				(hide yes)
			)
		)
		(property "License" "Apache-2.0"
			(at 156.21 229.87 0)
			(effects
				(font
					(size 1.27 1.27)
					(thickness 0.15)
				)
				(justify left bottom)
				(hide yes)
			)
		)
		(pin "1"
		)
		(instances
			(project "sdi-mipi-video-converter"
				(path ""
					(reference "#PWR0202")
					(unit 1)
				)
			)
		)
	)
	(symbol
		(lib_id "antmicroCapacitors0603:C_10u_0603")
		(at 137.16 91.44 90)
		(unit 1)
		(exclude_from_sim no)
		(in_bom yes)
		(on_board yes)
		(dnp no)
		(fields_autoplaced yes)
		(property "Reference" "C92"
			(at 139.7 87.6235 90)
			(effects
				(font
					(size 1.27 1.27)
					(thickness 0.15)
				)
				(justify right)
			)
		)
		(property "Value" "C_10u_0603"
			(at 147.32 71.12 0)
			(effects
				(font
					(size 1.27 1.27)
					(thickness 0.15)
				)
				(justify left bottom)
				(hide yes)
			)
		)
		(property "Footprint" "antmicro-footprints:C_0603_1608Metric"
			(at 149.86 71.12 0)
			(effects
				(font
					(size 1.27 1.27)
					(thickness 0.15)
				)
				(justify left bottom)
				(hide yes)
			)
		)
		(property "Datasheet" "https://www.murata.com/products/productdetail?partno=GRM188R61A106KE69%23"
			(at 152.4 71.12 0)
			(effects
				(font
					(size 1.27 1.27)
					(thickness 0.15)
				)
				(justify left bottom)
				(hide yes)
			)
		)
		(property "Description" "SMD Multilayer Ceramic Capacitor, 10 µF, 10 V, 0603 [1608 Metric], ± 10%, X5R, GRM Series"
			(at 137.16 91.44 0)
			(effects
				(font
					(size 1.27 1.27)
				)
				(hide yes)
			)
		)
		(property "Manufacturer" "Murata"
			(at 157.48 71.12 0)
			(effects
				(font
					(size 1.27 1.27)
					(thickness 0.15)
				)
				(justify left bottom)
				(hide yes)
			)
		)
		(property "MPN" "GRM188R61A106KE69D"
			(at 154.94 71.12 0)
			(effects
				(font
					(size 1.27 1.27)
					(thickness 0.15)
				)
				(justify left bottom)
				(hide yes)
			)
		)
		(property "Val" "10u"
			(at 139.7 90.1635 90)
			(effects
				(font
					(size 1.27 1.27)
					(thickness 0.15)
				)
				(justify right)
			)
		)
		(property "License" "Apache-2.0"
			(at 160.02 71.12 0)
			(effects
				(font
					(size 1.27 1.27)
					(thickness 0.15)
				)
				(justify left bottom)
				(hide yes)
			)
		)
		(property "Author" "Antmicro"
			(at 162.56 71.12 0)
			(effects
				(font
					(size 1.27 1.27)
					(thickness 0.15)
				)
				(justify left bottom)
				(hide yes)
			)
		)
		(property "Voltage" ""
			(at 165.1 71.12 0)
			(effects
				(font
					(size 1.27 1.27)
				)
				(justify left bottom)
				(hide yes)
			)
		)
		(property "Dielectric" "template_dielectric"
			(at 167.64 71.12 0)
			(effects
				(font
					(size 1.27 1.27)
				)
				(justify left bottom)
				(hide yes)
			)
		)
		(pin "1"
		)
		(pin "2"
		)
		(instances
			(project "sdi-mipi-video-converter"
				(path ""
					(reference "C92")
					(unit 1)
				)
			)
		)
	)
	(symbol
		(lib_id "antmicropower:GND")
		(at 176.53 92.71 0)
		(mirror y)
		(unit 1)
		(exclude_from_sim no)
		(in_bom yes)
		(on_board yes)
		(dnp no)
		(property "Reference" "#PWR0205"
			(at 167.64 95.25 0)
			(effects
				(font
					(size 1.27 1.27)
					(thickness 0.15)
				)
				(justify left bottom)
				(hide yes)
			)
		)
		(property "Value" "GND"
			(at 178.435 97.79 0)
			(effects
				(font
					(size 1.27 1.27)
					(thickness 0.15)
				)
				(justify left)
			)
		)
		(property "Footprint" ""
			(at 167.64 100.33 0)
			(effects
				(font
					(size 1.27 1.27)
					(thickness 0.15)
				)
				(justify left bottom)
				(hide yes)
			)
		)
		(property "Datasheet" ""
			(at 167.64 105.41 0)
			(effects
				(font
					(size 1.27 1.27)
					(thickness 0.15)
				)
				(justify left bottom)
				(hide yes)
			)
		)
		(property "Description" ""
			(at 176.53 92.71 0)
			(effects
				(font
					(size 1.27 1.27)
				)
				(hide yes)
			)
		)
		(property "Author" "Antmicro"
			(at 167.64 100.33 0)
			(effects
				(font
					(size 1.27 1.27)
					(thickness 0.15)
				)
				(justify left bottom)
				(hide yes)
			)
		)
		(property "License" "Apache-2.0"
			(at 167.64 102.87 0)
			(effects
				(font
					(size 1.27 1.27)
					(thickness 0.15)
				)
				(justify left bottom)
				(hide yes)
			)
		)
		(pin "1"
		)
		(instances
			(project "sdi-mipi-video-converter"
				(path ""
					(reference "#PWR0205")
					(unit 1)
				)
			)
		)
	)
	(symbol
		(lib_id "antmicroCapacitorsmisc:C_100n_0201")
		(at 176.53 55.88 90)
		(unit 1)
		(exclude_from_sim no)
		(in_bom yes)
		(on_board yes)
		(dnp no)
		(fields_autoplaced yes)
		(property "Reference" "C98"
			(at 179.07 52.0635 90)
			(effects
				(font
					(size 1.27 1.27)
					(thickness 0.15)
				)
				(justify right)
			)
		)
		(property "Value" "C_100n_0201"
			(at 186.69 35.56 0)
			(effects
				(font
					(size 1.27 1.27)
					(thickness 0.15)
				)
				(justify left bottom)
				(hide yes)
			)
		)
		(property "Footprint" "antmicro-footprints:C_0201"
			(at 189.23 35.56 0)
			(effects
				(font
					(size 1.27 1.27)
					(thickness 0.15)
				)
				(justify left bottom)
				(hide yes)
			)
		)
		(property "Datasheet" "https://www.yageo.com/en/Chart/Download/pdf/CC0201KRX6S5BB104"
			(at 191.77 35.56 0)
			(effects
				(font
					(size 1.27 1.27)
					(thickness 0.15)
				)
				(justify left bottom)
				(hide yes)
			)
		)
		(property "Description" "SMD Multilayer Ceramic Capacitor, 0.1 µF, 6.3 V, 0201 [0603 Metric], ± 10%, X6S, CC Series"
			(at 176.53 55.88 0)
			(effects
				(font
					(size 1.27 1.27)
				)
				(hide yes)
			)
		)
		(property "Manufacturer" "YAGEO"
			(at 196.85 35.56 0)
			(effects
				(font
					(size 1.27 1.27)
					(thickness 0.15)
				)
				(justify left bottom)
				(hide yes)
			)
		)
		(property "MPN" "CC0201KRX6S5BB104"
			(at 194.31 35.56 0)
			(effects
				(font
					(size 1.27 1.27)
					(thickness 0.15)
				)
				(justify left bottom)
				(hide yes)
			)
		)
		(property "Val" "100n"
			(at 179.07 54.6035 90)
			(effects
				(font
					(size 1.27 1.27)
					(thickness 0.15)
				)
				(justify right)
			)
		)
		(property "License" "Apache-2.0"
			(at 199.39 35.56 0)
			(effects
				(font
					(size 1.27 1.27)
					(thickness 0.15)
				)
				(justify left bottom)
				(hide yes)
			)
		)
		(property "Author" "Antmicro"
			(at 201.93 35.56 0)
			(effects
				(font
					(size 1.27 1.27)
					(thickness 0.15)
				)
				(justify left bottom)
				(hide yes)
			)
		)
		(property "Voltage" ""
			(at 204.47 35.56 0)
			(effects
				(font
					(size 1.27 1.27)
				)
				(justify left bottom)
				(hide yes)
			)
		)
		(property "Dielectric" ""
			(at 207.01 35.56 0)
			(effects
				(font
					(size 1.27 1.27)
				)
				(justify left bottom)
				(hide yes)
			)
		)
		(property "Public" "False"
			(at 209.55 35.56 0)
			(effects
				(font
					(size 1.27 1.27)
				)
				(justify left bottom)
				(hide yes)
			)
		)
		(pin "1"
		)
		(pin "2"
		)
		(instances
			(project "sdi-mipi-video-converter"
				(path ""
					(reference "C98")
					(unit 1)
				)
			)
		)
	)
	(symbol
		(lib_id "antmicropower:GND")
		(at 199.39 92.71 0)
		(mirror y)
		(unit 1)
		(exclude_from_sim no)
		(in_bom yes)
		(on_board yes)
		(dnp no)
		(fields_autoplaced yes)
		(property "Reference" "#PWR0212"
			(at 190.5 95.25 0)
			(effects
				(font
					(size 1.27 1.27)
					(thickness 0.15)
				)
				(justify left bottom)
				(hide yes)
			)
		)
		(property "Value" "GND"
			(at 199.39 97.79 0)
			(effects
				(font
					(size 1.27 1.27)
					(thickness 0.15)
				)
			)
		)
		(property "Footprint" ""
			(at 190.5 100.33 0)
			(effects
				(font
					(size 1.27 1.27)
					(thickness 0.15)
				)
				(justify left bottom)
				(hide yes)
			)
		)
		(property "Datasheet" ""
			(at 190.5 105.41 0)
			(effects
				(font
					(size 1.27 1.27)
					(thickness 0.15)
				)
				(justify left bottom)
				(hide yes)
			)
		)
		(property "Description" ""
			(at 199.39 92.71 0)
			(effects
				(font
					(size 1.27 1.27)
				)
				(hide yes)
			)
		)
		(property "Author" "Antmicro"
			(at 190.5 100.33 0)
			(effects
				(font
					(size 1.27 1.27)
					(thickness 0.15)
				)
				(justify left bottom)
				(hide yes)
			)
		)
		(property "License" "Apache-2.0"
			(at 190.5 102.87 0)
			(effects
				(font
					(size 1.27 1.27)
					(thickness 0.15)
				)
				(justify left bottom)
				(hide yes)
			)
		)
		(pin "1"
		)
		(instances
			(project "sdi-mipi-video-converter"
				(path ""
					(reference "#PWR0212")
					(unit 1)
				)
			)
		)
	)
	(symbol
		(lib_id "antmicropower:GND")
		(at 176.53 219.71 0)
		(mirror y)
		(unit 1)
		(exclude_from_sim no)
		(in_bom yes)
		(on_board yes)
		(dnp no)
		(fields_autoplaced yes)
		(property "Reference" "#PWR0208"
			(at 167.64 222.25 0)
			(effects
				(font
					(size 1.27 1.27)
					(thickness 0.15)
				)
				(justify left bottom)
				(hide yes)
			)
		)
		(property "Value" "GND"
			(at 176.53 224.79 0)
			(effects
				(font
					(size 1.27 1.27)
					(thickness 0.15)
				)
			)
		)
		(property "Footprint" ""
			(at 167.64 227.33 0)
			(effects
				(font
					(size 1.27 1.27)
					(thickness 0.15)
				)
				(justify left bottom)
				(hide yes)
			)
		)
		(property "Datasheet" ""
			(at 167.64 232.41 0)
			(effects
				(font
					(size 1.27 1.27)
					(thickness 0.15)
				)
				(justify left bottom)
				(hide yes)
			)
		)
		(property "Description" ""
			(at 176.53 219.71 0)
			(effects
				(font
					(size 1.27 1.27)
				)
				(hide yes)
			)
		)
		(property "Author" "Antmicro"
			(at 167.64 227.33 0)
			(effects
				(font
					(size 1.27 1.27)
					(thickness 0.15)
				)
				(justify left bottom)
				(hide yes)
			)
		)
		(property "License" "Apache-2.0"
			(at 167.64 229.87 0)
			(effects
				(font
					(size 1.27 1.27)
					(thickness 0.15)
				)
				(justify left bottom)
				(hide yes)
			)
		)
		(pin "1"
		)
		(instances
			(project "sdi-mipi-video-converter"
				(path ""
					(reference "#PWR0208")
					(unit 1)
				)
			)
		)
	)
	(symbol
		(lib_id "antmicropower:GND")
		(at 187.96 57.15 0)
		(mirror y)
		(unit 1)
		(exclude_from_sim no)
		(in_bom yes)
		(on_board yes)
		(dnp no)
		(property "Reference" "#PWR0210"
			(at 179.07 59.69 0)
			(effects
				(font
					(size 1.27 1.27)
					(thickness 0.15)
				)
				(justify left bottom)
				(hide yes)
			)
		)
		(property "Value" "GND"
			(at 187.96 61.595 0)
			(effects
				(font
					(size 1.27 1.27)
					(thickness 0.15)
				)
			)
		)
		(property "Footprint" ""
			(at 179.07 64.77 0)
			(effects
				(font
					(size 1.27 1.27)
					(thickness 0.15)
				)
				(justify left bottom)
				(hide yes)
			)
		)
		(property "Datasheet" ""
			(at 179.07 69.85 0)
			(effects
				(font
					(size 1.27 1.27)
					(thickness 0.15)
				)
				(justify left bottom)
				(hide yes)
			)
		)
		(property "Description" ""
			(at 187.96 57.15 0)
			(effects
				(font
					(size 1.27 1.27)
				)
				(hide yes)
			)
		)
		(property "Author" "Antmicro"
			(at 179.07 64.77 0)
			(effects
				(font
					(size 1.27 1.27)
					(thickness 0.15)
				)
				(justify left bottom)
				(hide yes)
			)
		)
		(property "License" "Apache-2.0"
			(at 179.07 67.31 0)
			(effects
				(font
					(size 1.27 1.27)
					(thickness 0.15)
				)
				(justify left bottom)
				(hide yes)
			)
		)
		(pin "1"
		)
		(instances
			(project "sdi-mipi-video-converter"
				(path ""
					(reference "#PWR0210")
					(unit 1)
				)
			)
		)
	)
	(symbol
		(lib_id "antmicroCapacitorsmisc:C_100n_0201")
		(at 176.53 266.7 90)
		(unit 1)
		(exclude_from_sim no)
		(in_bom yes)
		(on_board yes)
		(dnp no)
		(fields_autoplaced yes)
		(property "Reference" "C103"
			(at 179.07 262.8835 90)
			(effects
				(font
					(size 1.27 1.27)
					(thickness 0.15)
				)
				(justify right)
			)
		)
		(property "Value" "C_100n_0201"
			(at 186.69 246.38 0)
			(effects
				(font
					(size 1.27 1.27)
					(thickness 0.15)
				)
				(justify left bottom)
				(hide yes)
			)
		)
		(property "Footprint" "antmicro-footprints:C_0201"
			(at 189.23 246.38 0)
			(effects
				(font
					(size 1.27 1.27)
					(thickness 0.15)
				)
				(justify left bottom)
				(hide yes)
			)
		)
		(property "Datasheet" "https://www.yageo.com/en/Chart/Download/pdf/CC0201KRX6S5BB104"
			(at 191.77 246.38 0)
			(effects
				(font
					(size 1.27 1.27)
					(thickness 0.15)
				)
				(justify left bottom)
				(hide yes)
			)
		)
		(property "Description" "SMD Multilayer Ceramic Capacitor, 0.1 µF, 6.3 V, 0201 [0603 Metric], ± 10%, X6S, CC Series"
			(at 176.53 266.7 0)
			(effects
				(font
					(size 1.27 1.27)
				)
				(hide yes)
			)
		)
		(property "Manufacturer" "YAGEO"
			(at 196.85 246.38 0)
			(effects
				(font
					(size 1.27 1.27)
					(thickness 0.15)
				)
				(justify left bottom)
				(hide yes)
			)
		)
		(property "MPN" "CC0201KRX6S5BB104"
			(at 194.31 246.38 0)
			(effects
				(font
					(size 1.27 1.27)
					(thickness 0.15)
				)
				(justify left bottom)
				(hide yes)
			)
		)
		(property "Val" "100n"
			(at 179.07 265.4235 90)
			(effects
				(font
					(size 1.27 1.27)
					(thickness 0.15)
				)
				(justify right)
			)
		)
		(property "License" "Apache-2.0"
			(at 199.39 246.38 0)
			(effects
				(font
					(size 1.27 1.27)
					(thickness 0.15)
				)
				(justify left bottom)
				(hide yes)
			)
		)
		(property "Author" "Antmicro"
			(at 201.93 246.38 0)
			(effects
				(font
					(size 1.27 1.27)
					(thickness 0.15)
				)
				(justify left bottom)
				(hide yes)
			)
		)
		(property "Voltage" ""
			(at 204.47 246.38 0)
			(effects
				(font
					(size 1.27 1.27)
				)
				(justify left bottom)
				(hide yes)
			)
		)
		(property "Dielectric" ""
			(at 207.01 246.38 0)
			(effects
				(font
					(size 1.27 1.27)
				)
				(justify left bottom)
				(hide yes)
			)
		)
		(property "Public" "False"
			(at 209.55 246.38 0)
			(effects
				(font
					(size 1.27 1.27)
				)
				(justify left bottom)
				(hide yes)
			)
		)
		(pin "1"
		)
		(pin "2"
		)
		(instances
			(project "sdi-mipi-video-converter"
				(path ""
					(reference "C103")
					(unit 1)
				)
			)
		)
	)
	(symbol
		(lib_id "antmicropower:GND")
		(at 176.53 129.54 0)
		(mirror y)
		(unit 1)
		(exclude_from_sim no)
		(in_bom yes)
		(on_board yes)
		(dnp no)
		(fields_autoplaced yes)
		(property "Reference" "#PWR0206"
			(at 167.64 132.08 0)
			(effects
				(font
					(size 1.27 1.27)
					(thickness 0.15)
				)
				(justify left bottom)
				(hide yes)
			)
		)
		(property "Value" "GND"
			(at 176.53 134.62 0)
			(effects
				(font
					(size 1.27 1.27)
					(thickness 0.15)
				)
			)
		)
		(property "Footprint" ""
			(at 167.64 137.16 0)
			(effects
				(font
					(size 1.27 1.27)
					(thickness 0.15)
				)
				(justify left bottom)
				(hide yes)
			)
		)
		(property "Datasheet" ""
			(at 167.64 142.24 0)
			(effects
				(font
					(size 1.27 1.27)
					(thickness 0.15)
				)
				(justify left bottom)
				(hide yes)
			)
		)
		(property "Description" ""
			(at 176.53 129.54 0)
			(effects
				(font
					(size 1.27 1.27)
				)
				(hide yes)
			)
		)
		(property "Author" "Antmicro"
			(at 167.64 137.16 0)
			(effects
				(font
					(size 1.27 1.27)
					(thickness 0.15)
				)
				(justify left bottom)
				(hide yes)
			)
		)
		(property "License" "Apache-2.0"
			(at 167.64 139.7 0)
			(effects
				(font
					(size 1.27 1.27)
					(thickness 0.15)
				)
				(justify left bottom)
				(hide yes)
			)
		)
		(pin "1"
		)
		(instances
			(project "sdi-mipi-video-converter"
				(path ""
					(reference "#PWR0206")
					(unit 1)
				)
			)
		)
	)
	(symbol
		(lib_id "antmicroCapacitorsmisc:C_100n_0201")
		(at 165.1 128.27 90)
		(unit 1)
		(exclude_from_sim no)
		(in_bom yes)
		(on_board yes)
		(dnp no)
		(fields_autoplaced yes)
		(property "Reference" "C94"
			(at 167.64 124.4535 90)
			(effects
				(font
					(size 1.27 1.27)
					(thickness 0.15)
				)
				(justify right)
			)
		)
		(property "Value" "C_100n_0201"
			(at 175.26 107.95 0)
			(effects
				(font
					(size 1.27 1.27)
					(thickness 0.15)
				)
				(justify left bottom)
				(hide yes)
			)
		)
		(property "Footprint" "antmicro-footprints:C_0201"
			(at 177.8 107.95 0)
			(effects
				(font
					(size 1.27 1.27)
					(thickness 0.15)
				)
				(justify left bottom)
				(hide yes)
			)
		)
		(property "Datasheet" "https://www.yageo.com/en/Chart/Download/pdf/CC0201KRX6S5BB104"
			(at 180.34 107.95 0)
			(effects
				(font
					(size 1.27 1.27)
					(thickness 0.15)
				)
				(justify left bottom)
				(hide yes)
			)
		)
		(property "Description" "SMD Multilayer Ceramic Capacitor, 0.1 µF, 6.3 V, 0201 [0603 Metric], ± 10%, X6S, CC Series"
			(at 165.1 128.27 0)
			(effects
				(font
					(size 1.27 1.27)
				)
				(hide yes)
			)
		)
		(property "Manufacturer" "YAGEO"
			(at 185.42 107.95 0)
			(effects
				(font
					(size 1.27 1.27)
					(thickness 0.15)
				)
				(justify left bottom)
				(hide yes)
			)
		)
		(property "MPN" "CC0201KRX6S5BB104"
			(at 182.88 107.95 0)
			(effects
				(font
					(size 1.27 1.27)
					(thickness 0.15)
				)
				(justify left bottom)
				(hide yes)
			)
		)
		(property "Val" "100n"
			(at 167.64 126.9935 90)
			(effects
				(font
					(size 1.27 1.27)
					(thickness 0.15)
				)
				(justify right)
			)
		)
		(property "License" "Apache-2.0"
			(at 187.96 107.95 0)
			(effects
				(font
					(size 1.27 1.27)
					(thickness 0.15)
				)
				(justify left bottom)
				(hide yes)
			)
		)
		(property "Author" "Antmicro"
			(at 190.5 107.95 0)
			(effects
				(font
					(size 1.27 1.27)
					(thickness 0.15)
				)
				(justify left bottom)
				(hide yes)
			)
		)
		(property "Voltage" ""
			(at 193.04 107.95 0)
			(effects
				(font
					(size 1.27 1.27)
				)
				(justify left bottom)
				(hide yes)
			)
		)
		(property "Dielectric" ""
			(at 195.58 107.95 0)
			(effects
				(font
					(size 1.27 1.27)
				)
				(justify left bottom)
				(hide yes)
			)
		)
		(property "Public" "False"
			(at 198.12 107.95 0)
			(effects
				(font
					(size 1.27 1.27)
				)
				(justify left bottom)
				(hide yes)
			)
		)
		(pin "1"
		)
		(pin "2"
		)
		(instances
			(project "sdi-mipi-video-converter"
				(path ""
					(reference "C94")
					(unit 1)
				)
			)
		)
	)
	(symbol
		(lib_id "antmicroCapacitors0603:C_10u_0603")
		(at 128.27 91.44 90)
		(unit 1)
		(exclude_from_sim no)
		(in_bom yes)
		(on_board yes)
		(dnp no)
		(fields_autoplaced yes)
		(property "Reference" "C87"
			(at 130.81 87.6235 90)
			(effects
				(font
					(size 1.27 1.27)
					(thickness 0.15)
				)
				(justify right)
			)
		)
		(property "Value" "C_10u_0603"
			(at 138.43 71.12 0)
			(effects
				(font
					(size 1.27 1.27)
					(thickness 0.15)
				)
				(justify left bottom)
				(hide yes)
			)
		)
		(property "Footprint" "antmicro-footprints:C_0603_1608Metric"
			(at 140.97 71.12 0)
			(effects
				(font
					(size 1.27 1.27)
					(thickness 0.15)
				)
				(justify left bottom)
				(hide yes)
			)
		)
		(property "Datasheet" "https://www.murata.com/products/productdetail?partno=GRM188R61A106KE69%23"
			(at 143.51 71.12 0)
			(effects
				(font
					(size 1.27 1.27)
					(thickness 0.15)
				)
				(justify left bottom)
				(hide yes)
			)
		)
		(property "Description" "SMD Multilayer Ceramic Capacitor, 10 µF, 10 V, 0603 [1608 Metric], ± 10%, X5R, GRM Series"
			(at 128.27 91.44 0)
			(effects
				(font
					(size 1.27 1.27)
				)
				(hide yes)
			)
		)
		(property "Manufacturer" "Murata"
			(at 148.59 71.12 0)
			(effects
				(font
					(size 1.27 1.27)
					(thickness 0.15)
				)
				(justify left bottom)
				(hide yes)
			)
		)
		(property "MPN" "GRM188R61A106KE69D"
			(at 146.05 71.12 0)
			(effects
				(font
					(size 1.27 1.27)
					(thickness 0.15)
				)
				(justify left bottom)
				(hide yes)
			)
		)
		(property "Val" "10u"
			(at 130.81 90.1635 90)
			(effects
				(font
					(size 1.27 1.27)
					(thickness 0.15)
				)
				(justify right)
			)
		)
		(property "License" "Apache-2.0"
			(at 151.13 71.12 0)
			(effects
				(font
					(size 1.27 1.27)
					(thickness 0.15)
				)
				(justify left bottom)
				(hide yes)
			)
		)
		(property "Author" "Antmicro"
			(at 153.67 71.12 0)
			(effects
				(font
					(size 1.27 1.27)
					(thickness 0.15)
				)
				(justify left bottom)
				(hide yes)
			)
		)
		(property "Voltage" ""
			(at 156.21 71.12 0)
			(effects
				(font
					(size 1.27 1.27)
				)
				(justify left bottom)
				(hide yes)
			)
		)
		(property "Dielectric" "template_dielectric"
			(at 158.75 71.12 0)
			(effects
				(font
					(size 1.27 1.27)
				)
				(justify left bottom)
				(hide yes)
			)
		)
		(pin "1"
		)
		(pin "2"
		)
		(instances
			(project "sdi-mipi-video-converter"
				(path ""
					(reference "C87")
					(unit 1)
				)
			)
		)
	)
	(symbol
		(lib_id "antmicroCapacitors0603:C_10u_0603")
		(at 128.27 218.44 90)
		(unit 1)
		(exclude_from_sim no)
		(in_bom yes)
		(on_board yes)
		(dnp no)
		(fields_autoplaced yes)
		(property "Reference" "C90"
			(at 130.81 214.6235 90)
			(effects
				(font
					(size 1.27 1.27)
					(thickness 0.15)
				)
				(justify right)
			)
		)
		(property "Value" "C_10u_0603"
			(at 138.43 198.12 0)
			(effects
				(font
					(size 1.27 1.27)
					(thickness 0.15)
				)
				(justify left bottom)
				(hide yes)
			)
		)
		(property "Footprint" "antmicro-footprints:C_0603_1608Metric"
			(at 140.97 198.12 0)
			(effects
				(font
					(size 1.27 1.27)
					(thickness 0.15)
				)
				(justify left bottom)
				(hide yes)
			)
		)
		(property "Datasheet" "https://www.murata.com/products/productdetail?partno=GRM188R61A106KE69%23"
			(at 143.51 198.12 0)
			(effects
				(font
					(size 1.27 1.27)
					(thickness 0.15)
				)
				(justify left bottom)
				(hide yes)
			)
		)
		(property "Description" "SMD Multilayer Ceramic Capacitor, 10 µF, 10 V, 0603 [1608 Metric], ± 10%, X5R, GRM Series"
			(at 128.27 218.44 0)
			(effects
				(font
					(size 1.27 1.27)
				)
				(hide yes)
			)
		)
		(property "Manufacturer" "Murata"
			(at 148.59 198.12 0)
			(effects
				(font
					(size 1.27 1.27)
					(thickness 0.15)
				)
				(justify left bottom)
				(hide yes)
			)
		)
		(property "MPN" "GRM188R61A106KE69D"
			(at 146.05 198.12 0)
			(effects
				(font
					(size 1.27 1.27)
					(thickness 0.15)
				)
				(justify left bottom)
				(hide yes)
			)
		)
		(property "Val" "10u"
			(at 130.81 217.1635 90)
			(effects
				(font
					(size 1.27 1.27)
					(thickness 0.15)
				)
				(justify right)
			)
		)
		(property "License" "Apache-2.0"
			(at 151.13 198.12 0)
			(effects
				(font
					(size 1.27 1.27)
					(thickness 0.15)
				)
				(justify left bottom)
				(hide yes)
			)
		)
		(property "Author" "Antmicro"
			(at 153.67 198.12 0)
			(effects
				(font
					(size 1.27 1.27)
					(thickness 0.15)
				)
				(justify left bottom)
				(hide yes)
			)
		)
		(property "Voltage" ""
			(at 156.21 198.12 0)
			(effects
				(font
					(size 1.27 1.27)
				)
				(justify left bottom)
				(hide yes)
			)
		)
		(property "Dielectric" "template_dielectric"
			(at 158.75 198.12 0)
			(effects
				(font
					(size 1.27 1.27)
				)
				(justify left bottom)
				(hide yes)
			)
		)
		(pin "1"
		)
		(pin "2"
		)
		(instances
			(project "sdi-mipi-video-converter"
				(path ""
					(reference "C90")
					(unit 1)
				)
			)
		)
	)
	(symbol
		(lib_id "antmicropower:GND")
		(at 187.96 92.71 0)
		(mirror y)
		(unit 1)
		(exclude_from_sim no)
		(in_bom yes)
		(on_board yes)
		(dnp no)
		(fields_autoplaced yes)
		(property "Reference" "#PWR0211"
			(at 179.07 95.25 0)
			(effects
				(font
					(size 1.27 1.27)
					(thickness 0.15)
				)
				(justify left bottom)
				(hide yes)
			)
		)
		(property "Value" "GND"
			(at 187.96 97.79 0)
			(effects
				(font
					(size 1.27 1.27)
					(thickness 0.15)
				)
			)
		)
		(property "Footprint" ""
			(at 179.07 100.33 0)
			(effects
				(font
					(size 1.27 1.27)
					(thickness 0.15)
				)
				(justify left bottom)
				(hide yes)
			)
		)
		(property "Datasheet" ""
			(at 179.07 105.41 0)
			(effects
				(font
					(size 1.27 1.27)
					(thickness 0.15)
				)
				(justify left bottom)
				(hide yes)
			)
		)
		(property "Description" ""
			(at 187.96 92.71 0)
			(effects
				(font
					(size 1.27 1.27)
				)
				(hide yes)
			)
		)
		(property "Author" "Antmicro"
			(at 179.07 100.33 0)
			(effects
				(font
					(size 1.27 1.27)
					(thickness 0.15)
				)
				(justify left bottom)
				(hide yes)
			)
		)
		(property "License" "Apache-2.0"
			(at 179.07 102.87 0)
			(effects
				(font
					(size 1.27 1.27)
					(thickness 0.15)
				)
				(justify left bottom)
				(hide yes)
			)
		)
		(pin "1"
		)
		(instances
			(project "sdi-mipi-video-converter"
				(path ""
					(reference "#PWR0211")
					(unit 1)
				)
			)
		)
	)
	(symbol
		(lib_id "antmicropower:+1V8")
		(at 128.27 109.22 0)
		(unit 1)
		(exclude_from_sim no)
		(in_bom yes)
		(on_board yes)
		(dnp no)
		(fields_autoplaced yes)
		(property "Reference" "#PWR0190"
			(at 143.51 111.76 0)
			(effects
				(font
					(size 1.27 1.27)
					(thickness 0.15)
				)
				(justify left bottom)
				(hide yes)
			)
		)
		(property "Value" "+1V8"
			(at 128.27 104.14 0)
			(effects
				(font
					(size 1.27 1.27)
					(thickness 0.15)
				)
			)
		)
		(property "Footprint" ""
			(at 143.51 116.84 0)
			(effects
				(font
					(size 1.27 1.27)
					(thickness 0.15)
				)
				(justify left bottom)
				(hide yes)
			)
		)
		(property "Datasheet" ""
			(at 143.51 119.38 0)
			(effects
				(font
					(size 1.27 1.27)
					(thickness 0.15)
				)
				(justify left bottom)
				(hide yes)
			)
		)
		(property "Description" ""
			(at 128.27 109.22 0)
			(effects
				(font
					(size 1.27 1.27)
				)
				(hide yes)
			)
		)
		(property "Author" "Antmicro"
			(at 143.51 116.84 0)
			(effects
				(font
					(size 1.27 1.27)
					(thickness 0.15)
				)
				(justify left bottom)
				(hide yes)
			)
		)
		(property "License" "Apache-2.0"
			(at 143.51 119.38 0)
			(effects
				(font
					(size 1.27 1.27)
					(thickness 0.15)
				)
				(justify left bottom)
				(hide yes)
			)
		)
		(pin "1"
		)
		(instances
			(project "sdi-mipi-video-converter"
				(path ""
					(reference "#PWR0190")
					(unit 1)
				)
			)
		)
	)
	(symbol
		(lib_id "antmicropower:GND")
		(at 176.53 57.15 0)
		(mirror y)
		(unit 1)
		(exclude_from_sim no)
		(in_bom yes)
		(on_board yes)
		(dnp no)
		(property "Reference" "#PWR0204"
			(at 167.64 59.69 0)
			(effects
				(font
					(size 1.27 1.27)
					(thickness 0.15)
				)
				(justify left bottom)
				(hide yes)
			)
		)
		(property "Value" "GND"
			(at 176.53 61.595 0)
			(effects
				(font
					(size 1.27 1.27)
					(thickness 0.15)
				)
			)
		)
		(property "Footprint" ""
			(at 167.64 64.77 0)
			(effects
				(font
					(size 1.27 1.27)
					(thickness 0.15)
				)
				(justify left bottom)
				(hide yes)
			)
		)
		(property "Datasheet" ""
			(at 167.64 69.85 0)
			(effects
				(font
					(size 1.27 1.27)
					(thickness 0.15)
				)
				(justify left bottom)
				(hide yes)
			)
		)
		(property "Description" ""
			(at 176.53 57.15 0)
			(effects
				(font
					(size 1.27 1.27)
				)
				(hide yes)
			)
		)
		(property "Author" "Antmicro"
			(at 167.64 64.77 0)
			(effects
				(font
					(size 1.27 1.27)
					(thickness 0.15)
				)
				(justify left bottom)
				(hide yes)
			)
		)
		(property "License" "Apache-2.0"
			(at 167.64 67.31 0)
			(effects
				(font
					(size 1.27 1.27)
					(thickness 0.15)
				)
				(justify left bottom)
				(hide yes)
			)
		)
		(pin "1"
		)
		(instances
			(project "sdi-mipi-video-converter"
				(path ""
					(reference "#PWR0204")
					(unit 1)
				)
			)
		)
	)
	(symbol
		(lib_id "antmicroCapacitorsmisc:C_100n_0201")
		(at 165.1 91.44 90)
		(unit 1)
		(exclude_from_sim no)
		(in_bom yes)
		(on_board yes)
		(dnp no)
		(fields_autoplaced yes)
		(property "Reference" "C93"
			(at 167.64 87.6235 90)
			(effects
				(font
					(size 1.27 1.27)
					(thickness 0.15)
				)
				(justify right)
			)
		)
		(property "Value" "C_100n_0201"
			(at 175.26 71.12 0)
			(effects
				(font
					(size 1.27 1.27)
					(thickness 0.15)
				)
				(justify left bottom)
				(hide yes)
			)
		)
		(property "Footprint" "antmicro-footprints:C_0201"
			(at 177.8 71.12 0)
			(effects
				(font
					(size 1.27 1.27)
					(thickness 0.15)
				)
				(justify left bottom)
				(hide yes)
			)
		)
		(property "Datasheet" "https://www.yageo.com/en/Chart/Download/pdf/CC0201KRX6S5BB104"
			(at 180.34 71.12 0)
			(effects
				(font
					(size 1.27 1.27)
					(thickness 0.15)
				)
				(justify left bottom)
				(hide yes)
			)
		)
		(property "Description" "SMD Multilayer Ceramic Capacitor, 0.1 µF, 6.3 V, 0201 [0603 Metric], ± 10%, X6S, CC Series"
			(at 165.1 91.44 0)
			(effects
				(font
					(size 1.27 1.27)
				)
				(hide yes)
			)
		)
		(property "Manufacturer" "YAGEO"
			(at 185.42 71.12 0)
			(effects
				(font
					(size 1.27 1.27)
					(thickness 0.15)
				)
				(justify left bottom)
				(hide yes)
			)
		)
		(property "MPN" "CC0201KRX6S5BB104"
			(at 182.88 71.12 0)
			(effects
				(font
					(size 1.27 1.27)
					(thickness 0.15)
				)
				(justify left bottom)
				(hide yes)
			)
		)
		(property "Val" "100n"
			(at 167.64 90.1635 90)
			(effects
				(font
					(size 1.27 1.27)
					(thickness 0.15)
				)
				(justify right)
			)
		)
		(property "License" "Apache-2.0"
			(at 187.96 71.12 0)
			(effects
				(font
					(size 1.27 1.27)
					(thickness 0.15)
				)
				(justify left bottom)
				(hide yes)
			)
		)
		(property "Author" "Antmicro"
			(at 190.5 71.12 0)
			(effects
				(font
					(size 1.27 1.27)
					(thickness 0.15)
				)
				(justify left bottom)
				(hide yes)
			)
		)
		(property "Voltage" ""
			(at 193.04 71.12 0)
			(effects
				(font
					(size 1.27 1.27)
				)
				(justify left bottom)
				(hide yes)
			)
		)
		(property "Dielectric" ""
			(at 195.58 71.12 0)
			(effects
				(font
					(size 1.27 1.27)
				)
				(justify left bottom)
				(hide yes)
			)
		)
		(property "Public" "False"
			(at 198.12 71.12 0)
			(effects
				(font
					(size 1.27 1.27)
				)
				(justify left bottom)
				(hide yes)
			)
		)
		(pin "1"
		)
		(pin "2"
		)
		(instances
			(project "sdi-mipi-video-converter"
				(path ""
					(reference "C93")
					(unit 1)
				)
			)
		)
	)
	(symbol
		(lib_id "antmicroCapacitors0603:C_10u_0603")
		(at 128.27 266.7 90)
		(unit 1)
		(exclude_from_sim no)
		(in_bom yes)
		(on_board yes)
		(dnp no)
		(fields_autoplaced yes)
		(property "Reference" "C91"
			(at 130.81 262.8835 90)
			(effects
				(font
					(size 1.27 1.27)
					(thickness 0.15)
				)
				(justify right)
			)
		)
		(property "Value" "C_10u_0603"
			(at 138.43 246.38 0)
			(effects
				(font
					(size 1.27 1.27)
					(thickness 0.15)
				)
				(justify left bottom)
				(hide yes)
			)
		)
		(property "Footprint" "antmicro-footprints:C_0603_1608Metric"
			(at 140.97 246.38 0)
			(effects
				(font
					(size 1.27 1.27)
					(thickness 0.15)
				)
				(justify left bottom)
				(hide yes)
			)
		)
		(property "Datasheet" "https://www.murata.com/products/productdetail?partno=GRM188R61A106KE69%23"
			(at 143.51 246.38 0)
			(effects
				(font
					(size 1.27 1.27)
					(thickness 0.15)
				)
				(justify left bottom)
				(hide yes)
			)
		)
		(property "Description" "SMD Multilayer Ceramic Capacitor, 10 µF, 10 V, 0603 [1608 Metric], ± 10%, X5R, GRM Series"
			(at 128.27 266.7 0)
			(effects
				(font
					(size 1.27 1.27)
				)
				(hide yes)
			)
		)
		(property "Manufacturer" "Murata"
			(at 148.59 246.38 0)
			(effects
				(font
					(size 1.27 1.27)
					(thickness 0.15)
				)
				(justify left bottom)
				(hide yes)
			)
		)
		(property "MPN" "GRM188R61A106KE69D"
			(at 146.05 246.38 0)
			(effects
				(font
					(size 1.27 1.27)
					(thickness 0.15)
				)
				(justify left bottom)
				(hide yes)
			)
		)
		(property "Val" "10u"
			(at 130.81 265.4235 90)
			(effects
				(font
					(size 1.27 1.27)
					(thickness 0.15)
				)
				(justify right)
			)
		)
		(property "License" "Apache-2.0"
			(at 151.13 246.38 0)
			(effects
				(font
					(size 1.27 1.27)
					(thickness 0.15)
				)
				(justify left bottom)
				(hide yes)
			)
		)
		(property "Author" "Antmicro"
			(at 153.67 246.38 0)
			(effects
				(font
					(size 1.27 1.27)
					(thickness 0.15)
				)
				(justify left bottom)
				(hide yes)
			)
		)
		(property "Voltage" ""
			(at 156.21 246.38 0)
			(effects
				(font
					(size 1.27 1.27)
				)
				(justify left bottom)
				(hide yes)
			)
		)
		(property "Dielectric" "template_dielectric"
			(at 158.75 246.38 0)
			(effects
				(font
					(size 1.27 1.27)
				)
				(justify left bottom)
				(hide yes)
			)
		)
		(pin "1"
		)
		(pin "2"
		)
		(instances
			(project "sdi-mipi-video-converter"
				(path ""
					(reference "C91")
					(unit 1)
				)
			)
		)
	)
	(symbol
		(lib_id "antmicroCapacitorsmisc:C_100n_0201")
		(at 165.1 173.99 90)
		(unit 1)
		(exclude_from_sim no)
		(in_bom yes)
		(on_board yes)
		(dnp no)
		(fields_autoplaced yes)
		(property "Reference" "C95"
			(at 167.64 170.1735 90)
			(effects
				(font
					(size 1.27 1.27)
					(thickness 0.15)
				)
				(justify right)
			)
		)
		(property "Value" "C_100n_0201"
			(at 175.26 153.67 0)
			(effects
				(font
					(size 1.27 1.27)
					(thickness 0.15)
				)
				(justify left bottom)
				(hide yes)
			)
		)
		(property "Footprint" "antmicro-footprints:C_0201"
			(at 177.8 153.67 0)
			(effects
				(font
					(size 1.27 1.27)
					(thickness 0.15)
				)
				(justify left bottom)
				(hide yes)
			)
		)
		(property "Datasheet" "https://www.yageo.com/en/Chart/Download/pdf/CC0201KRX6S5BB104"
			(at 180.34 153.67 0)
			(effects
				(font
					(size 1.27 1.27)
					(thickness 0.15)
				)
				(justify left bottom)
				(hide yes)
			)
		)
		(property "Description" "SMD Multilayer Ceramic Capacitor, 0.1 µF, 6.3 V, 0201 [0603 Metric], ± 10%, X6S, CC Series"
			(at 165.1 173.99 0)
			(effects
				(font
					(size 1.27 1.27)
				)
				(hide yes)
			)
		)
		(property "Manufacturer" "YAGEO"
			(at 185.42 153.67 0)
			(effects
				(font
					(size 1.27 1.27)
					(thickness 0.15)
				)
				(justify left bottom)
				(hide yes)
			)
		)
		(property "MPN" "CC0201KRX6S5BB104"
			(at 182.88 153.67 0)
			(effects
				(font
					(size 1.27 1.27)
					(thickness 0.15)
				)
				(justify left bottom)
				(hide yes)
			)
		)
		(property "Val" "100n"
			(at 167.64 172.7135 90)
			(effects
				(font
					(size 1.27 1.27)
					(thickness 0.15)
				)
				(justify right)
			)
		)
		(property "License" "Apache-2.0"
			(at 187.96 153.67 0)
			(effects
				(font
					(size 1.27 1.27)
					(thickness 0.15)
				)
				(justify left bottom)
				(hide yes)
			)
		)
		(property "Author" "Antmicro"
			(at 190.5 153.67 0)
			(effects
				(font
					(size 1.27 1.27)
					(thickness 0.15)
				)
				(justify left bottom)
				(hide yes)
			)
		)
		(property "Voltage" ""
			(at 193.04 153.67 0)
			(effects
				(font
					(size 1.27 1.27)
				)
				(justify left bottom)
				(hide yes)
			)
		)
		(property "Dielectric" ""
			(at 195.58 153.67 0)
			(effects
				(font
					(size 1.27 1.27)
				)
				(justify left bottom)
				(hide yes)
			)
		)
		(property "Public" "False"
			(at 198.12 153.67 0)
			(effects
				(font
					(size 1.27 1.27)
				)
				(justify left bottom)
				(hide yes)
			)
		)
		(pin "1"
		)
		(pin "2"
		)
		(instances
			(project "sdi-mipi-video-converter"
				(path ""
					(reference "C95")
					(unit 1)
				)
			)
		)
	)
	(symbol
		(lib_id "antmicroCapacitorsmisc:C_100n_0201")
		(at 165.1 55.88 90)
		(unit 1)
		(exclude_from_sim no)
		(in_bom yes)
		(on_board yes)
		(dnp no)
		(fields_autoplaced yes)
		(property "Reference" "C85"
			(at 167.64 52.0635 90)
			(effects
				(font
					(size 1.27 1.27)
					(thickness 0.15)
				)
				(justify right)
			)
		)
		(property "Value" "C_100n_0201"
			(at 175.26 35.56 0)
			(effects
				(font
					(size 1.27 1.27)
					(thickness 0.15)
				)
				(justify left bottom)
				(hide yes)
			)
		)
		(property "Footprint" "antmicro-footprints:C_0201"
			(at 177.8 35.56 0)
			(effects
				(font
					(size 1.27 1.27)
					(thickness 0.15)
				)
				(justify left bottom)
				(hide yes)
			)
		)
		(property "Datasheet" "https://www.yageo.com/en/Chart/Download/pdf/CC0201KRX6S5BB104"
			(at 180.34 35.56 0)
			(effects
				(font
					(size 1.27 1.27)
					(thickness 0.15)
				)
				(justify left bottom)
				(hide yes)
			)
		)
		(property "Description" "SMD Multilayer Ceramic Capacitor, 0.1 µF, 6.3 V, 0201 [0603 Metric], ± 10%, X6S, CC Series"
			(at 165.1 55.88 0)
			(effects
				(font
					(size 1.27 1.27)
				)
				(hide yes)
			)
		)
		(property "Manufacturer" "YAGEO"
			(at 185.42 35.56 0)
			(effects
				(font
					(size 1.27 1.27)
					(thickness 0.15)
				)
				(justify left bottom)
				(hide yes)
			)
		)
		(property "MPN" "CC0201KRX6S5BB104"
			(at 182.88 35.56 0)
			(effects
				(font
					(size 1.27 1.27)
					(thickness 0.15)
				)
				(justify left bottom)
				(hide yes)
			)
		)
		(property "Val" "100n"
			(at 167.64 54.6035 90)
			(effects
				(font
					(size 1.27 1.27)
					(thickness 0.15)
				)
				(justify right)
			)
		)
		(property "License" "Apache-2.0"
			(at 187.96 35.56 0)
			(effects
				(font
					(size 1.27 1.27)
					(thickness 0.15)
				)
				(justify left bottom)
				(hide yes)
			)
		)
		(property "Author" "Antmicro"
			(at 190.5 35.56 0)
			(effects
				(font
					(size 1.27 1.27)
					(thickness 0.15)
				)
				(justify left bottom)
				(hide yes)
			)
		)
		(property "Voltage" ""
			(at 193.04 35.56 0)
			(effects
				(font
					(size 1.27 1.27)
				)
				(justify left bottom)
				(hide yes)
			)
		)
		(property "Dielectric" ""
			(at 195.58 35.56 0)
			(effects
				(font
					(size 1.27 1.27)
				)
				(justify left bottom)
				(hide yes)
			)
		)
		(property "Public" "False"
			(at 198.12 35.56 0)
			(effects
				(font
					(size 1.27 1.27)
				)
				(justify left bottom)
				(hide yes)
			)
		)
		(pin "1"
		)
		(pin "2"
		)
		(instances
			(project "sdi-mipi-video-converter"
				(path ""
					(reference "C85")
					(unit 1)
				)
			)
		)
	)
	(symbol
		(lib_id "antmicropower:GND")
		(at 176.53 267.97 0)
		(mirror y)
		(unit 1)
		(exclude_from_sim no)
		(in_bom yes)
		(on_board yes)
		(dnp no)
		(fields_autoplaced yes)
		(property "Reference" "#PWR0209"
			(at 167.64 270.51 0)
			(effects
				(font
					(size 1.27 1.27)
					(thickness 0.15)
				)
				(justify left bottom)
				(hide yes)
			)
		)
		(property "Value" "GND"
			(at 176.53 273.05 0)
			(effects
				(font
					(size 1.27 1.27)
					(thickness 0.15)
				)
			)
		)
		(property "Footprint" ""
			(at 167.64 275.59 0)
			(effects
				(font
					(size 1.27 1.27)
					(thickness 0.15)
				)
				(justify left bottom)
				(hide yes)
			)
		)
		(property "Datasheet" ""
			(at 167.64 280.67 0)
			(effects
				(font
					(size 1.27 1.27)
					(thickness 0.15)
				)
				(justify left bottom)
				(hide yes)
			)
		)
		(property "Description" ""
			(at 176.53 267.97 0)
			(effects
				(font
					(size 1.27 1.27)
				)
				(hide yes)
			)
		)
		(property "Author" "Antmicro"
			(at 167.64 275.59 0)
			(effects
				(font
					(size 1.27 1.27)
					(thickness 0.15)
				)
				(justify left bottom)
				(hide yes)
			)
		)
		(property "License" "Apache-2.0"
			(at 167.64 278.13 0)
			(effects
				(font
					(size 1.27 1.27)
					(thickness 0.15)
				)
				(justify left bottom)
				(hide yes)
			)
		)
		(pin "1"
		)
		(instances
			(project "sdi-mipi-video-converter"
				(path ""
					(reference "#PWR0209")
					(unit 1)
				)
			)
		)
	)
	(symbol
		(lib_id "antmicropower:GND")
		(at 128.27 267.97 0)
		(mirror y)
		(unit 1)
		(exclude_from_sim no)
		(in_bom yes)
		(on_board yes)
		(dnp no)
		(fields_autoplaced yes)
		(property "Reference" "#PWR0196"
			(at 119.38 270.51 0)
			(effects
				(font
					(size 1.27 1.27)
					(thickness 0.15)
				)
				(justify left bottom)
				(hide yes)
			)
		)
		(property "Value" "GND"
			(at 128.27 273.05 0)
			(effects
				(font
					(size 1.27 1.27)
					(thickness 0.15)
				)
			)
		)
		(property "Footprint" ""
			(at 119.38 275.59 0)
			(effects
				(font
					(size 1.27 1.27)
					(thickness 0.15)
				)
				(justify left bottom)
				(hide yes)
			)
		)
		(property "Datasheet" ""
			(at 119.38 280.67 0)
			(effects
				(font
					(size 1.27 1.27)
					(thickness 0.15)
				)
				(justify left bottom)
				(hide yes)
			)
		)
		(property "Description" ""
			(at 128.27 267.97 0)
			(effects
				(font
					(size 1.27 1.27)
				)
				(hide yes)
			)
		)
		(property "Author" "Antmicro"
			(at 119.38 275.59 0)
			(effects
				(font
					(size 1.27 1.27)
					(thickness 0.15)
				)
				(justify left bottom)
				(hide yes)
			)
		)
		(property "License" "Apache-2.0"
			(at 119.38 278.13 0)
			(effects
				(font
					(size 1.27 1.27)
					(thickness 0.15)
				)
				(justify left bottom)
				(hide yes)
			)
		)
		(pin "1"
		)
		(instances
			(project "sdi-mipi-video-converter"
				(path ""
					(reference "#PWR0196")
					(unit 1)
				)
			)
		)
	)
	(symbol
		(lib_id "antmicropower:GND")
		(at 165.1 129.54 0)
		(mirror y)
		(unit 1)
		(exclude_from_sim no)
		(in_bom yes)
		(on_board yes)
		(dnp no)
		(fields_autoplaced yes)
		(property "Reference" "#PWR0200"
			(at 156.21 132.08 0)
			(effects
				(font
					(size 1.27 1.27)
					(thickness 0.15)
				)
				(justify left bottom)
				(hide yes)
			)
		)
		(property "Value" "GND"
			(at 165.1 134.62 0)
			(effects
				(font
					(size 1.27 1.27)
					(thickness 0.15)
				)
			)
		)
		(property "Footprint" ""
			(at 156.21 137.16 0)
			(effects
				(font
					(size 1.27 1.27)
					(thickness 0.15)
				)
				(justify left bottom)
				(hide yes)
			)
		)
		(property "Datasheet" ""
			(at 156.21 142.24 0)
			(effects
				(font
					(size 1.27 1.27)
					(thickness 0.15)
				)
				(justify left bottom)
				(hide yes)
			)
		)
		(property "Description" ""
			(at 165.1 129.54 0)
			(effects
				(font
					(size 1.27 1.27)
				)
				(hide yes)
			)
		)
		(property "Author" "Antmicro"
			(at 156.21 137.16 0)
			(effects
				(font
					(size 1.27 1.27)
					(thickness 0.15)
				)
				(justify left bottom)
				(hide yes)
			)
		)
		(property "License" "Apache-2.0"
			(at 156.21 139.7 0)
			(effects
				(font
					(size 1.27 1.27)
					(thickness 0.15)
				)
				(justify left bottom)
				(hide yes)
			)
		)
		(pin "1"
		)
		(instances
			(project "sdi-mipi-video-converter"
				(path ""
					(reference "#PWR0200")
					(unit 1)
				)
			)
		)
	)
	(symbol
		(lib_id "antmicroFPGAChips:CrossLink_LIFCL-40-9BG256C")
		(at 255.27 116.84 0)
		(unit 13)
		(exclude_from_sim no)
		(in_bom yes)
		(on_board yes)
		(dnp no)
		(fields_autoplaced yes)
		(property "Reference" "U11"
			(at 271.78 109.22 0)
			(effects
				(font
					(size 1.27 1.27)
					(thickness 0.15)
				)
			)
		)
		(property "Value" "LIFCL-40-9BG256C"
			(at 271.78 109.22 0)
			(effects
				(font
					(size 1.27 1.27)
					(thickness 0.15)
				)
				(hide yes)
			)
		)
		(property "Footprint" "antmicro-footprints:BGA-256_14x14mm_Layout16x16_P0.8mm"
			(at 308.61 124.46 0)
			(effects
				(font
					(size 1.27 1.27)
					(thickness 0.15)
				)
				(justify left bottom)
				(hide yes)
			)
		)
		(property "Datasheet" "https://www.latticesemi.com/-/media/LatticeSemi/Documents/DataSheets/CrossLink/FPGA-DS-02007-2-1-CrossLink-Family-Data-Sheet.ashx?document_id=51662"
			(at 308.61 127 0)
			(effects
				(font
					(size 1.27 1.27)
					(thickness 0.15)
				)
				(justify left bottom)
				(hide yes)
			)
		)
		(property "Description" "CrossLink-NX™ Field Programmable Gate Array 256-LFBGA"
			(at 255.27 116.84 0)
			(effects
				(font
					(size 1.27 1.27)
				)
				(hide yes)
			)
		)
		(property "MPN" "LIFCL-40-9BG256C"
			(at 271.78 111.76 0)
			(effects
				(font
					(size 1.27 1.27)
					(thickness 0.15)
				)
			)
		)
		(property "Manufacturer" "Lattice Semiconductor"
			(at 308.61 129.54 0)
			(effects
				(font
					(size 1.27 1.27)
					(thickness 0.15)
				)
				(justify left bottom)
				(hide yes)
			)
		)
		(property "Author" "Antmicro"
			(at 308.61 132.08 0)
			(effects
				(font
					(size 1.27 1.27)
					(thickness 0.15)
				)
				(justify left bottom)
				(hide yes)
			)
		)
		(property "License" "Apache-2.0"
			(at 308.61 134.62 0)
			(effects
				(font
					(size 1.27 1.27)
					(thickness 0.15)
				)
				(justify left bottom)
				(hide yes)
			)
		)
		(pin "B16"
		)
		(pin "C12"
		)
		(pin "C13"
		)
		(pin "C14"
		)
		(pin "C15"
		)
		(pin "C16"
		)
		(pin "D11"
		)
		(pin "D12"
		)
		(pin "D13"
		)
		(pin "D15"
		)
		(pin "D16"
		)
		(pin "E15"
		)
		(pin "E16"
		)
		(pin "D10"
		)
		(pin "E10"
		)
		(pin "E11"
		)
		(pin "E12"
		)
		(pin "E13"
		)
		(pin "E14"
		)
		(pin "E9"
		)
		(pin "F10"
		)
		(pin "F11"
		)
		(pin "F13"
		)
		(pin "F14"
		)
		(pin "F15"
		)
		(pin "F16"
		)
		(pin "F9"
		)
		(pin "G10"
		)
		(pin "G11"
		)
		(pin "G12"
		)
		(pin "G13"
		)
		(pin "G14"
		)
		(pin "G15"
		)
		(pin "G16"
		)
		(pin "G9"
		)
		(pin "H10"
		)
		(pin "H11"
		)
		(pin "H12"
		)
		(pin "H13"
		)
		(pin "H14"
		)
		(pin "H15"
		)
		(pin "H16"
		)
		(pin "J11"
		)
		(pin "J12"
		)
		(pin "J13"
		)
		(pin "J15"
		)
		(pin "J16"
		)
		(pin "K11"
		)
		(pin "K12"
		)
		(pin "L10"
		)
		(pin "L11"
		)
		(pin "L12"
		)
		(pin "M11"
		)
		(pin "M12"
		)
		(pin "M13"
		)
		(pin "M14"
		)
		(pin "M15"
		)
		(pin "M16"
		)
		(pin "N11"
		)
		(pin "N12"
		)
		(pin "N13"
		)
		(pin "N14"
		)
		(pin "N15"
		)
		(pin "N16"
		)
		(pin "P10"
		)
		(pin "P11"
		)
		(pin "P12"
		)
		(pin "P14"
		)
		(pin "P15"
		)
		(pin "P16"
		)
		(pin "R10"
		)
		(pin "R11"
		)
		(pin "R12"
		)
		(pin "R13"
		)
		(pin "R14"
		)
		(pin "R15"
		)
		(pin "R16"
		)
		(pin "T11"
		)
		(pin "T12"
		)
		(pin "T13"
		)
		(pin "T14"
		)
		(pin "T15"
		)
		(pin "L8"
		)
		(pin "L9"
		)
		(pin "M10"
		)
		(pin "M8"
		)
		(pin "M9"
		)
		(pin "N10"
		)
		(pin "N6"
		)
		(pin "N8"
		)
		(pin "N9"
		)
		(pin "P4"
		)
		(pin "P5"
		)
		(pin "P6"
		)
		(pin "P7"
		)
		(pin "P8"
		)
		(pin "P9"
		)
		(pin "R1"
		)
		(pin "R2"
		)
		(pin "R3"
		)
		(pin "R4"
		)
		(pin "R5"
		)
		(pin "R6"
		)
		(pin "R7"
		)
		(pin "R8"
		)
		(pin "R9"
		)
		(pin "T10"
		)
		(pin "T2"
		)
		(pin "T3"
		)
		(pin "T4"
		)
		(pin "T5"
		)
		(pin "T6"
		)
		(pin "T7"
		)
		(pin "T8"
		)
		(pin "T9"
		)
		(pin "K7"
		)
		(pin "L6"
		)
		(pin "L7"
		)
		(pin "M4"
		)
		(pin "M7"
		)
		(pin "N3"
		)
		(pin "N4"
		)
		(pin "N5"
		)
		(pin "P1"
		)
		(pin "P2"
		)
		(pin "P3"
		)
		(pin "H1"
		)
		(pin "H2"
		)
		(pin "H3"
		)
		(pin "H4"
		)
		(pin "H5"
		)
		(pin "H6"
		)
		(pin "J1"
		)
		(pin "J2"
		)
		(pin "J4"
		)
		(pin "J5"
		)
		(pin "J6"
		)
		(pin "K1"
		)
		(pin "K2"
		)
		(pin "K3"
		)
		(pin "K4"
		)
		(pin "K5"
		)
		(pin "K6"
		)
		(pin "L1"
		)
		(pin "L2"
		)
		(pin "L3"
		)
		(pin "L4"
		)
		(pin "L5"
		)
		(pin "M1"
		)
		(pin "M2"
		)
		(pin "M3"
		)
		(pin "N1"
		)
		(pin "N2"
		)
		(pin "D4"
		)
		(pin "D5"
		)
		(pin "D6"
		)
		(pin "E4"
		)
		(pin "E5"
		)
		(pin "E6"
		)
		(pin "F4"
		)
		(pin "F5"
		)
		(pin "F6"
		)
		(pin "G3"
		)
		(pin "G4"
		)
		(pin "G6"
		)
		(pin "B1"
		)
		(pin "B2"
		)
		(pin "C1"
		)
		(pin "C2"
		)
		(pin "D1"
		)
		(pin "D2"
		)
		(pin "E1"
		)
		(pin "E2"
		)
		(pin "F1"
		)
		(pin "F2"
		)
		(pin "A3"
		)
		(pin "A4"
		)
		(pin "A5"
		)
		(pin "A6"
		)
		(pin "A7"
		)
		(pin "B3"
		)
		(pin "B4"
		)
		(pin "B5"
		)
		(pin "B6"
		)
		(pin "B7"
		)
		(pin "K13"
		)
		(pin "K14"
		)
		(pin "K15"
		)
		(pin "K16"
		)
		(pin "L13"
		)
		(pin "L14"
		)
		(pin "L15"
		)
		(pin "L16"
		)
		(pin "A11"
		)
		(pin "A12"
		)
		(pin "A14"
		)
		(pin "A15"
		)
		(pin "A9"
		)
		(pin "B12"
		)
		(pin "B9"
		)
		(pin "C11"
		)
		(pin "A1"
		)
		(pin "A10"
		)
		(pin "A13"
		)
		(pin "A16"
		)
		(pin "A2"
		)
		(pin "A8"
		)
		(pin "B10"
		)
		(pin "B11"
		)
		(pin "B13"
		)
		(pin "B14"
		)
		(pin "B15"
		)
		(pin "B8"
		)
		(pin "C10"
		)
		(pin "C3"
		)
		(pin "C4"
		)
		(pin "C5"
		)
		(pin "C6"
		)
		(pin "C7"
		)
		(pin "C8"
		)
		(pin "C9"
		)
		(pin "D14"
		)
		(pin "D3"
		)
		(pin "D7"
		)
		(pin "D8"
		)
		(pin "D9"
		)
		(pin "E3"
		)
		(pin "E7"
		)
		(pin "E8"
		)
		(pin "F12"
		)
		(pin "F3"
		)
		(pin "F7"
		)
		(pin "F8"
		)
		(pin "G1"
		)
		(pin "G2"
		)
		(pin "G5"
		)
		(pin "G7"
		)
		(pin "G8"
		)
		(pin "H7"
		)
		(pin "H8"
		)
		(pin "H9"
		)
		(pin "J10"
		)
		(pin "J14"
		)
		(pin "J3"
		)
		(pin "J7"
		)
		(pin "J8"
		)
		(pin "J9"
		)
		(pin "K10"
		)
		(pin "K8"
		)
		(pin "K9"
		)
		(pin "M5"
		)
		(pin "M6"
		)
		(pin "N7"
		)
		(pin "P13"
		)
		(pin "T1"
		)
		(pin "T16"
		)
		(instances
			(project "sdi-mipi-video-converter"
				(path ""
					(reference "U11")
					(unit 13)
				)
			)
		)
	)
	(symbol
		(lib_id "antmicroCapacitorsmisc:C_100n_0201")
		(at 209.55 55.88 90)
		(unit 1)
		(exclude_from_sim no)
		(in_bom yes)
		(on_board yes)
		(dnp no)
		(fields_autoplaced yes)
		(property "Reference" "C107"
			(at 212.09 52.0635 90)
			(effects
				(font
					(size 1.27 1.27)
					(thickness 0.15)
				)
				(justify right)
			)
		)
		(property "Value" "C_100n_0201"
			(at 219.71 35.56 0)
			(effects
				(font
					(size 1.27 1.27)
					(thickness 0.15)
				)
				(justify left bottom)
				(hide yes)
			)
		)
		(property "Footprint" "antmicro-footprints:C_0201"
			(at 222.25 35.56 0)
			(effects
				(font
					(size 1.27 1.27)
					(thickness 0.15)
				)
				(justify left bottom)
				(hide yes)
			)
		)
		(property "Datasheet" "https://www.yageo.com/en/Chart/Download/pdf/CC0201KRX6S5BB104"
			(at 224.79 35.56 0)
			(effects
				(font
					(size 1.27 1.27)
					(thickness 0.15)
				)
				(justify left bottom)
				(hide yes)
			)
		)
		(property "Description" "SMD Multilayer Ceramic Capacitor, 0.1 µF, 6.3 V, 0201 [0603 Metric], ± 10%, X6S, CC Series"
			(at 209.55 55.88 0)
			(effects
				(font
					(size 1.27 1.27)
				)
				(hide yes)
			)
		)
		(property "Manufacturer" "YAGEO"
			(at 229.87 35.56 0)
			(effects
				(font
					(size 1.27 1.27)
					(thickness 0.15)
				)
				(justify left bottom)
				(hide yes)
			)
		)
		(property "MPN" "CC0201KRX6S5BB104"
			(at 227.33 35.56 0)
			(effects
				(font
					(size 1.27 1.27)
					(thickness 0.15)
				)
				(justify left bottom)
				(hide yes)
			)
		)
		(property "Val" "100n"
			(at 212.09 54.6035 90)
			(effects
				(font
					(size 1.27 1.27)
					(thickness 0.15)
				)
				(justify right)
			)
		)
		(property "License" "Apache-2.0"
			(at 232.41 35.56 0)
			(effects
				(font
					(size 1.27 1.27)
					(thickness 0.15)
				)
				(justify left bottom)
				(hide yes)
			)
		)
		(property "Author" "Antmicro"
			(at 234.95 35.56 0)
			(effects
				(font
					(size 1.27 1.27)
					(thickness 0.15)
				)
				(justify left bottom)
				(hide yes)
			)
		)
		(property "Voltage" ""
			(at 237.49 35.56 0)
			(effects
				(font
					(size 1.27 1.27)
				)
				(justify left bottom)
				(hide yes)
			)
		)
		(property "Dielectric" ""
			(at 240.03 35.56 0)
			(effects
				(font
					(size 1.27 1.27)
				)
				(justify left bottom)
				(hide yes)
			)
		)
		(property "Public" "False"
			(at 242.57 35.56 0)
			(effects
				(font
					(size 1.27 1.27)
				)
				(justify left bottom)
				(hide yes)
			)
		)
		(pin "1"
		)
		(pin "2"
		)
		(instances
			(project "sdi-mipi-video-converter"
				(path ""
					(reference "C107")
					(unit 1)
				)
			)
		)
	)
	(symbol
		(lib_id "antmicropower:GND")
		(at 128.27 92.71 0)
		(mirror y)
		(unit 1)
		(exclude_from_sim no)
		(in_bom yes)
		(on_board yes)
		(dnp no)
		(property "Reference" "#PWR0189"
			(at 119.38 95.25 0)
			(effects
				(font
					(size 1.27 1.27)
					(thickness 0.15)
				)
				(justify left bottom)
				(hide yes)
			)
		)
		(property "Value" "GND"
			(at 130.175 97.79 0)
			(effects
				(font
					(size 1.27 1.27)
					(thickness 0.15)
				)
				(justify left)
			)
		)
		(property "Footprint" ""
			(at 119.38 100.33 0)
			(effects
				(font
					(size 1.27 1.27)
					(thickness 0.15)
				)
				(justify left bottom)
				(hide yes)
			)
		)
		(property "Datasheet" ""
			(at 119.38 105.41 0)
			(effects
				(font
					(size 1.27 1.27)
					(thickness 0.15)
				)
				(justify left bottom)
				(hide yes)
			)
		)
		(property "Description" ""
			(at 128.27 92.71 0)
			(effects
				(font
					(size 1.27 1.27)
				)
				(hide yes)
			)
		)
		(property "Author" "Antmicro"
			(at 119.38 100.33 0)
			(effects
				(font
					(size 1.27 1.27)
					(thickness 0.15)
				)
				(justify left bottom)
				(hide yes)
			)
		)
		(property "License" "Apache-2.0"
			(at 119.38 102.87 0)
			(effects
				(font
					(size 1.27 1.27)
					(thickness 0.15)
				)
				(justify left bottom)
				(hide yes)
			)
		)
		(pin "1"
		)
		(instances
			(project "sdi-mipi-video-converter"
				(path ""
					(reference "#PWR0189")
					(unit 1)
				)
			)
		)
	)
	(symbol
		(lib_id "antmicroCapacitorsmisc:C_100n_0201")
		(at 176.53 91.44 90)
		(unit 1)
		(exclude_from_sim no)
		(in_bom yes)
		(on_board yes)
		(dnp no)
		(fields_autoplaced yes)
		(property "Reference" "C99"
			(at 179.07 87.6235 90)
			(effects
				(font
					(size 1.27 1.27)
					(thickness 0.15)
				)
				(justify right)
			)
		)
		(property "Value" "C_100n_0201"
			(at 186.69 71.12 0)
			(effects
				(font
					(size 1.27 1.27)
					(thickness 0.15)
				)
				(justify left bottom)
				(hide yes)
			)
		)
		(property "Footprint" "antmicro-footprints:C_0201"
			(at 189.23 71.12 0)
			(effects
				(font
					(size 1.27 1.27)
					(thickness 0.15)
				)
				(justify left bottom)
				(hide yes)
			)
		)
		(property "Datasheet" "https://www.yageo.com/en/Chart/Download/pdf/CC0201KRX6S5BB104"
			(at 191.77 71.12 0)
			(effects
				(font
					(size 1.27 1.27)
					(thickness 0.15)
				)
				(justify left bottom)
				(hide yes)
			)
		)
		(property "Description" "SMD Multilayer Ceramic Capacitor, 0.1 µF, 6.3 V, 0201 [0603 Metric], ± 10%, X6S, CC Series"
			(at 176.53 91.44 0)
			(effects
				(font
					(size 1.27 1.27)
				)
				(hide yes)
			)
		)
		(property "Manufacturer" "YAGEO"
			(at 196.85 71.12 0)
			(effects
				(font
					(size 1.27 1.27)
					(thickness 0.15)
				)
				(justify left bottom)
				(hide yes)
			)
		)
		(property "MPN" "CC0201KRX6S5BB104"
			(at 194.31 71.12 0)
			(effects
				(font
					(size 1.27 1.27)
					(thickness 0.15)
				)
				(justify left bottom)
				(hide yes)
			)
		)
		(property "Val" "100n"
			(at 179.07 90.1635 90)
			(effects
				(font
					(size 1.27 1.27)
					(thickness 0.15)
				)
				(justify right)
			)
		)
		(property "License" "Apache-2.0"
			(at 199.39 71.12 0)
			(effects
				(font
					(size 1.27 1.27)
					(thickness 0.15)
				)
				(justify left bottom)
				(hide yes)
			)
		)
		(property "Author" "Antmicro"
			(at 201.93 71.12 0)
			(effects
				(font
					(size 1.27 1.27)
					(thickness 0.15)
				)
				(justify left bottom)
				(hide yes)
			)
		)
		(property "Voltage" ""
			(at 204.47 71.12 0)
			(effects
				(font
					(size 1.27 1.27)
				)
				(justify left bottom)
				(hide yes)
			)
		)
		(property "Dielectric" ""
			(at 207.01 71.12 0)
			(effects
				(font
					(size 1.27 1.27)
				)
				(justify left bottom)
				(hide yes)
			)
		)
		(property "Public" "False"
			(at 209.55 71.12 0)
			(effects
				(font
					(size 1.27 1.27)
				)
				(justify left bottom)
				(hide yes)
			)
		)
		(pin "1"
		)
		(pin "2"
		)
		(instances
			(project "sdi-mipi-video-converter"
				(path ""
					(reference "C99")
					(unit 1)
				)
			)
		)
	)
	(symbol
		(lib_id "antmicroCapacitorsmisc:C_100n_0201")
		(at 176.53 173.99 90)
		(unit 1)
		(exclude_from_sim no)
		(in_bom yes)
		(on_board yes)
		(dnp no)
		(fields_autoplaced yes)
		(property "Reference" "C101"
			(at 179.07 170.1735 90)
			(effects
				(font
					(size 1.27 1.27)
					(thickness 0.15)
				)
				(justify right)
			)
		)
		(property "Value" "C_100n_0201"
			(at 186.69 153.67 0)
			(effects
				(font
					(size 1.27 1.27)
					(thickness 0.15)
				)
				(justify left bottom)
				(hide yes)
			)
		)
		(property "Footprint" "antmicro-footprints:C_0201"
			(at 189.23 153.67 0)
			(effects
				(font
					(size 1.27 1.27)
					(thickness 0.15)
				)
				(justify left bottom)
				(hide yes)
			)
		)
		(property "Datasheet" "https://www.yageo.com/en/Chart/Download/pdf/CC0201KRX6S5BB104"
			(at 191.77 153.67 0)
			(effects
				(font
					(size 1.27 1.27)
					(thickness 0.15)
				)
				(justify left bottom)
				(hide yes)
			)
		)
		(property "Description" "SMD Multilayer Ceramic Capacitor, 0.1 µF, 6.3 V, 0201 [0603 Metric], ± 10%, X6S, CC Series"
			(at 176.53 173.99 0)
			(effects
				(font
					(size 1.27 1.27)
				)
				(hide yes)
			)
		)
		(property "Manufacturer" "YAGEO"
			(at 196.85 153.67 0)
			(effects
				(font
					(size 1.27 1.27)
					(thickness 0.15)
				)
				(justify left bottom)
				(hide yes)
			)
		)
		(property "MPN" "CC0201KRX6S5BB104"
			(at 194.31 153.67 0)
			(effects
				(font
					(size 1.27 1.27)
					(thickness 0.15)
				)
				(justify left bottom)
				(hide yes)
			)
		)
		(property "Val" "100n"
			(at 179.07 172.7135 90)
			(effects
				(font
					(size 1.27 1.27)
					(thickness 0.15)
				)
				(justify right)
			)
		)
		(property "License" "Apache-2.0"
			(at 199.39 153.67 0)
			(effects
				(font
					(size 1.27 1.27)
					(thickness 0.15)
				)
				(justify left bottom)
				(hide yes)
			)
		)
		(property "Author" "Antmicro"
			(at 201.93 153.67 0)
			(effects
				(font
					(size 1.27 1.27)
					(thickness 0.15)
				)
				(justify left bottom)
				(hide yes)
			)
		)
		(property "Voltage" ""
			(at 204.47 153.67 0)
			(effects
				(font
					(size 1.27 1.27)
				)
				(justify left bottom)
				(hide yes)
			)
		)
		(property "Dielectric" ""
			(at 207.01 153.67 0)
			(effects
				(font
					(size 1.27 1.27)
				)
				(justify left bottom)
				(hide yes)
			)
		)
		(property "Public" "False"
			(at 209.55 153.67 0)
			(effects
				(font
					(size 1.27 1.27)
				)
				(justify left bottom)
				(hide yes)
			)
		)
		(pin "1"
		)
		(pin "2"
		)
		(instances
			(project "sdi-mipi-video-converter"
				(path ""
					(reference "C101")
					(unit 1)
				)
			)
		)
	)
	(symbol
		(lib_id "antmicropower:+1V8")
		(at 128.27 72.39 0)
		(unit 1)
		(exclude_from_sim no)
		(in_bom yes)
		(on_board yes)
		(dnp no)
		(fields_autoplaced yes)
		(property "Reference" "#PWR0188"
			(at 143.51 74.93 0)
			(effects
				(font
					(size 1.27 1.27)
					(thickness 0.15)
				)
				(justify left bottom)
				(hide yes)
			)
		)
		(property "Value" "+1V8"
			(at 128.27 67.31 0)
			(effects
				(font
					(size 1.27 1.27)
					(thickness 0.15)
				)
			)
		)
		(property "Footprint" ""
			(at 143.51 80.01 0)
			(effects
				(font
					(size 1.27 1.27)
					(thickness 0.15)
				)
				(justify left bottom)
				(hide yes)
			)
		)
		(property "Datasheet" ""
			(at 143.51 82.55 0)
			(effects
				(font
					(size 1.27 1.27)
					(thickness 0.15)
				)
				(justify left bottom)
				(hide yes)
			)
		)
		(property "Description" ""
			(at 128.27 72.39 0)
			(effects
				(font
					(size 1.27 1.27)
				)
				(hide yes)
			)
		)
		(property "Author" "Antmicro"
			(at 143.51 80.01 0)
			(effects
				(font
					(size 1.27 1.27)
					(thickness 0.15)
				)
				(justify left bottom)
				(hide yes)
			)
		)
		(property "License" "Apache-2.0"
			(at 143.51 82.55 0)
			(effects
				(font
					(size 1.27 1.27)
					(thickness 0.15)
				)
				(justify left bottom)
				(hide yes)
			)
		)
		(pin "1"
		)
		(instances
			(project "sdi-mipi-video-converter"
				(path ""
					(reference "#PWR0188")
					(unit 1)
				)
			)
		)
	)
	(symbol
		(lib_id "antmicropower:GND")
		(at 137.16 92.71 0)
		(mirror y)
		(unit 1)
		(exclude_from_sim no)
		(in_bom yes)
		(on_board yes)
		(dnp no)
		(fields_autoplaced yes)
		(property "Reference" "#PWR0197"
			(at 128.27 95.25 0)
			(effects
				(font
					(size 1.27 1.27)
					(thickness 0.15)
				)
				(justify left bottom)
				(hide yes)
			)
		)
		(property "Value" "GND"
			(at 137.16 97.79 0)
			(effects
				(font
					(size 1.27 1.27)
					(thickness 0.15)
				)
			)
		)
		(property "Footprint" ""
			(at 128.27 100.33 0)
			(effects
				(font
					(size 1.27 1.27)
					(thickness 0.15)
				)
				(justify left bottom)
				(hide yes)
			)
		)
		(property "Datasheet" ""
			(at 128.27 105.41 0)
			(effects
				(font
					(size 1.27 1.27)
					(thickness 0.15)
				)
				(justify left bottom)
				(hide yes)
			)
		)
		(property "Description" ""
			(at 137.16 92.71 0)
			(effects
				(font
					(size 1.27 1.27)
				)
				(hide yes)
			)
		)
		(property "Author" "Antmicro"
			(at 128.27 100.33 0)
			(effects
				(font
					(size 1.27 1.27)
					(thickness 0.15)
				)
				(justify left bottom)
				(hide yes)
			)
		)
		(property "License" "Apache-2.0"
			(at 128.27 102.87 0)
			(effects
				(font
					(size 1.27 1.27)
					(thickness 0.15)
				)
				(justify left bottom)
				(hide yes)
			)
		)
		(pin "1"
		)
		(instances
			(project "sdi-mipi-video-converter"
				(path ""
					(reference "#PWR0197")
					(unit 1)
				)
			)
		)
	)
	(symbol
		(lib_id "antmicroCapacitors0603:C_10u_0603")
		(at 128.27 173.99 90)
		(unit 1)
		(exclude_from_sim no)
		(in_bom yes)
		(on_board yes)
		(dnp no)
		(fields_autoplaced yes)
		(property "Reference" "C89"
			(at 130.81 170.1735 90)
			(effects
				(font
					(size 1.27 1.27)
					(thickness 0.15)
				)
				(justify right)
			)
		)
		(property "Value" "C_10u_0603"
			(at 138.43 153.67 0)
			(effects
				(font
					(size 1.27 1.27)
					(thickness 0.15)
				)
				(justify left bottom)
				(hide yes)
			)
		)
		(property "Footprint" "antmicro-footprints:C_0603_1608Metric"
			(at 140.97 153.67 0)
			(effects
				(font
					(size 1.27 1.27)
					(thickness 0.15)
				)
				(justify left bottom)
				(hide yes)
			)
		)
		(property "Datasheet" "https://www.murata.com/products/productdetail?partno=GRM188R61A106KE69%23"
			(at 143.51 153.67 0)
			(effects
				(font
					(size 1.27 1.27)
					(thickness 0.15)
				)
				(justify left bottom)
				(hide yes)
			)
		)
		(property "Description" "SMD Multilayer Ceramic Capacitor, 10 µF, 10 V, 0603 [1608 Metric], ± 10%, X5R, GRM Series"
			(at 128.27 173.99 0)
			(effects
				(font
					(size 1.27 1.27)
				)
				(hide yes)
			)
		)
		(property "Manufacturer" "Murata"
			(at 148.59 153.67 0)
			(effects
				(font
					(size 1.27 1.27)
					(thickness 0.15)
				)
				(justify left bottom)
				(hide yes)
			)
		)
		(property "MPN" "GRM188R61A106KE69D"
			(at 146.05 153.67 0)
			(effects
				(font
					(size 1.27 1.27)
					(thickness 0.15)
				)
				(justify left bottom)
				(hide yes)
			)
		)
		(property "Val" "10u"
			(at 130.81 172.7135 90)
			(effects
				(font
					(size 1.27 1.27)
					(thickness 0.15)
				)
				(justify right)
			)
		)
		(property "License" "Apache-2.0"
			(at 151.13 153.67 0)
			(effects
				(font
					(size 1.27 1.27)
					(thickness 0.15)
				)
				(justify left bottom)
				(hide yes)
			)
		)
		(property "Author" "Antmicro"
			(at 153.67 153.67 0)
			(effects
				(font
					(size 1.27 1.27)
					(thickness 0.15)
				)
				(justify left bottom)
				(hide yes)
			)
		)
		(property "Voltage" ""
			(at 156.21 153.67 0)
			(effects
				(font
					(size 1.27 1.27)
				)
				(justify left bottom)
				(hide yes)
			)
		)
		(property "Dielectric" "template_dielectric"
			(at 158.75 153.67 0)
			(effects
				(font
					(size 1.27 1.27)
				)
				(justify left bottom)
				(hide yes)
			)
		)
		(pin "1"
		)
		(pin "2"
		)
		(instances
			(project "sdi-mipi-video-converter"
				(path ""
					(reference "C89")
					(unit 1)
				)
			)
		)
	)
	(symbol
		(lib_id "antmicroCapacitors0603:C_10u_0603")
		(at 138.43 54.61 90)
		(unit 1)
		(exclude_from_sim no)
		(in_bom yes)
		(on_board yes)
		(dnp no)
		(fields_autoplaced yes)
		(property "Reference" "C116"
			(at 135.89 50.7935 90)
			(effects
				(font
					(size 1.27 1.27)
					(thickness 0.15)
				)
				(justify left)
			)
		)
		(property "Value" "C_10u_0603"
			(at 148.59 34.29 0)
			(effects
				(font
					(size 1.27 1.27)
					(thickness 0.15)
				)
				(justify left bottom)
				(hide yes)
			)
		)
		(property "Footprint" "antmicro-footprints:C_0603_1608Metric"
			(at 151.13 34.29 0)
			(effects
				(font
					(size 1.27 1.27)
					(thickness 0.15)
				)
				(justify left bottom)
				(hide yes)
			)
		)
		(property "Datasheet" "https://www.murata.com/products/productdetail?partno=GRM188R61A106KE69%23"
			(at 153.67 34.29 0)
			(effects
				(font
					(size 1.27 1.27)
					(thickness 0.15)
				)
				(justify left bottom)
				(hide yes)
			)
		)
		(property "Description" "SMD Multilayer Ceramic Capacitor, 10 µF, 10 V, 0603 [1608 Metric], ± 10%, X5R, GRM Series"
			(at 138.43 54.61 0)
			(effects
				(font
					(size 1.27 1.27)
				)
				(hide yes)
			)
		)
		(property "Manufacturer" "Murata"
			(at 158.75 34.29 0)
			(effects
				(font
					(size 1.27 1.27)
					(thickness 0.15)
				)
				(justify left bottom)
				(hide yes)
			)
		)
		(property "MPN" "GRM188R61A106KE69D"
			(at 156.21 34.29 0)
			(effects
				(font
					(size 1.27 1.27)
					(thickness 0.15)
				)
				(justify left bottom)
				(hide yes)
			)
		)
		(property "Val" "10u"
			(at 135.89 53.3335 90)
			(effects
				(font
					(size 1.27 1.27)
					(thickness 0.15)
				)
				(justify left)
			)
		)
		(property "License" "Apache-2.0"
			(at 161.29 34.29 0)
			(effects
				(font
					(size 1.27 1.27)
					(thickness 0.15)
				)
				(justify left bottom)
				(hide yes)
			)
		)
		(property "Author" "Antmicro"
			(at 163.83 34.29 0)
			(effects
				(font
					(size 1.27 1.27)
					(thickness 0.15)
				)
				(justify left bottom)
				(hide yes)
			)
		)
		(property "Voltage" ""
			(at 166.37 34.29 0)
			(effects
				(font
					(size 1.27 1.27)
				)
				(justify left bottom)
				(hide yes)
			)
		)
		(property "Dielectric" "template_dielectric"
			(at 168.91 34.29 0)
			(effects
				(font
					(size 1.27 1.27)
				)
				(justify left bottom)
				(hide yes)
			)
		)
		(pin "1"
		)
		(pin "2"
		)
		(instances
			(project "sdi-mipi-video-converter"
				(path ""
					(reference "C116")
					(unit 1)
				)
			)
		)
	)
	(symbol
		(lib_id "antmicropower:GND")
		(at 128.27 55.88 0)
		(mirror y)
		(unit 1)
		(exclude_from_sim no)
		(in_bom yes)
		(on_board yes)
		(dnp no)
		(property "Reference" "#PWR0187"
			(at 119.38 58.42 0)
			(effects
				(font
					(size 1.27 1.27)
					(thickness 0.15)
				)
				(justify left bottom)
				(hide yes)
			)
		)
		(property "Value" "GND"
			(at 130.175 60.325 0)
			(effects
				(font
					(size 1.27 1.27)
					(thickness 0.15)
				)
				(justify left)
			)
		)
		(property "Footprint" ""
			(at 119.38 63.5 0)
			(effects
				(font
					(size 1.27 1.27)
					(thickness 0.15)
				)
				(justify left bottom)
				(hide yes)
			)
		)
		(property "Datasheet" ""
			(at 119.38 68.58 0)
			(effects
				(font
					(size 1.27 1.27)
					(thickness 0.15)
				)
				(justify left bottom)
				(hide yes)
			)
		)
		(property "Description" ""
			(at 128.27 55.88 0)
			(effects
				(font
					(size 1.27 1.27)
				)
				(hide yes)
			)
		)
		(property "Author" "Antmicro"
			(at 119.38 63.5 0)
			(effects
				(font
					(size 1.27 1.27)
					(thickness 0.15)
				)
				(justify left bottom)
				(hide yes)
			)
		)
		(property "License" "Apache-2.0"
			(at 119.38 66.04 0)
			(effects
				(font
					(size 1.27 1.27)
					(thickness 0.15)
				)
				(justify left bottom)
				(hide yes)
			)
		)
		(pin "1"
		)
		(instances
			(project "sdi-mipi-video-converter"
				(path ""
					(reference "#PWR0187")
					(unit 1)
				)
			)
		)
	)
	(symbol
		(lib_id "antmicroCapacitorsmisc:C_100n_0201")
		(at 199.39 91.44 90)
		(unit 1)
		(exclude_from_sim no)
		(in_bom yes)
		(on_board yes)
		(dnp no)
		(fields_autoplaced yes)
		(property "Reference" "C106"
			(at 201.93 87.6235 90)
			(effects
				(font
					(size 1.27 1.27)
					(thickness 0.15)
				)
				(justify right)
			)
		)
		(property "Value" "C_100n_0201"
			(at 209.55 71.12 0)
			(effects
				(font
					(size 1.27 1.27)
					(thickness 0.15)
				)
				(justify left bottom)
				(hide yes)
			)
		)
		(property "Footprint" "antmicro-footprints:C_0201"
			(at 212.09 71.12 0)
			(effects
				(font
					(size 1.27 1.27)
					(thickness 0.15)
				)
				(justify left bottom)
				(hide yes)
			)
		)
		(property "Datasheet" "https://www.yageo.com/en/Chart/Download/pdf/CC0201KRX6S5BB104"
			(at 214.63 71.12 0)
			(effects
				(font
					(size 1.27 1.27)
					(thickness 0.15)
				)
				(justify left bottom)
				(hide yes)
			)
		)
		(property "Description" "SMD Multilayer Ceramic Capacitor, 0.1 µF, 6.3 V, 0201 [0603 Metric], ± 10%, X6S, CC Series"
			(at 199.39 91.44 0)
			(effects
				(font
					(size 1.27 1.27)
				)
				(hide yes)
			)
		)
		(property "Manufacturer" "YAGEO"
			(at 219.71 71.12 0)
			(effects
				(font
					(size 1.27 1.27)
					(thickness 0.15)
				)
				(justify left bottom)
				(hide yes)
			)
		)
		(property "MPN" "CC0201KRX6S5BB104"
			(at 217.17 71.12 0)
			(effects
				(font
					(size 1.27 1.27)
					(thickness 0.15)
				)
				(justify left bottom)
				(hide yes)
			)
		)
		(property "Val" "100n"
			(at 201.93 90.1635 90)
			(effects
				(font
					(size 1.27 1.27)
					(thickness 0.15)
				)
				(justify right)
			)
		)
		(property "License" "Apache-2.0"
			(at 222.25 71.12 0)
			(effects
				(font
					(size 1.27 1.27)
					(thickness 0.15)
				)
				(justify left bottom)
				(hide yes)
			)
		)
		(property "Author" "Antmicro"
			(at 224.79 71.12 0)
			(effects
				(font
					(size 1.27 1.27)
					(thickness 0.15)
				)
				(justify left bottom)
				(hide yes)
			)
		)
		(property "Voltage" ""
			(at 227.33 71.12 0)
			(effects
				(font
					(size 1.27 1.27)
				)
				(justify left bottom)
				(hide yes)
			)
		)
		(property "Dielectric" ""
			(at 229.87 71.12 0)
			(effects
				(font
					(size 1.27 1.27)
				)
				(justify left bottom)
				(hide yes)
			)
		)
		(property "Public" "False"
			(at 232.41 71.12 0)
			(effects
				(font
					(size 1.27 1.27)
				)
				(justify left bottom)
				(hide yes)
			)
		)
		(pin "1"
		)
		(pin "2"
		)
		(instances
			(project "sdi-mipi-video-converter"
				(path ""
					(reference "C106")
					(unit 1)
				)
			)
		)
	)
	(symbol
		(lib_id "antmicroCapacitors0603:C_10u_0603")
		(at 128.27 128.27 90)
		(unit 1)
		(exclude_from_sim no)
		(in_bom yes)
		(on_board yes)
		(dnp no)
		(fields_autoplaced yes)
		(property "Reference" "C88"
			(at 130.81 124.4535 90)
			(effects
				(font
					(size 1.27 1.27)
					(thickness 0.15)
				)
				(justify right)
			)
		)
		(property "Value" "C_10u_0603"
			(at 138.43 107.95 0)
			(effects
				(font
					(size 1.27 1.27)
					(thickness 0.15)
				)
				(justify left bottom)
				(hide yes)
			)
		)
		(property "Footprint" "antmicro-footprints:C_0603_1608Metric"
			(at 140.97 107.95 0)
			(effects
				(font
					(size 1.27 1.27)
					(thickness 0.15)
				)
				(justify left bottom)
				(hide yes)
			)
		)
		(property "Datasheet" "https://www.murata.com/products/productdetail?partno=GRM188R61A106KE69%23"
			(at 143.51 107.95 0)
			(effects
				(font
					(size 1.27 1.27)
					(thickness 0.15)
				)
				(justify left bottom)
				(hide yes)
			)
		)
		(property "Description" "SMD Multilayer Ceramic Capacitor, 10 µF, 10 V, 0603 [1608 Metric], ± 10%, X5R, GRM Series"
			(at 128.27 128.27 0)
			(effects
				(font
					(size 1.27 1.27)
				)
				(hide yes)
			)
		)
		(property "Manufacturer" "Murata"
			(at 148.59 107.95 0)
			(effects
				(font
					(size 1.27 1.27)
					(thickness 0.15)
				)
				(justify left bottom)
				(hide yes)
			)
		)
		(property "MPN" "GRM188R61A106KE69D"
			(at 146.05 107.95 0)
			(effects
				(font
					(size 1.27 1.27)
					(thickness 0.15)
				)
				(justify left bottom)
				(hide yes)
			)
		)
		(property "Val" "10u"
			(at 130.81 126.9935 90)
			(effects
				(font
					(size 1.27 1.27)
					(thickness 0.15)
				)
				(justify right)
			)
		)
		(property "License" "Apache-2.0"
			(at 151.13 107.95 0)
			(effects
				(font
					(size 1.27 1.27)
					(thickness 0.15)
				)
				(justify left bottom)
				(hide yes)
			)
		)
		(property "Author" "Antmicro"
			(at 153.67 107.95 0)
			(effects
				(font
					(size 1.27 1.27)
					(thickness 0.15)
				)
				(justify left bottom)
				(hide yes)
			)
		)
		(property "Voltage" ""
			(at 156.21 107.95 0)
			(effects
				(font
					(size 1.27 1.27)
				)
				(justify left bottom)
				(hide yes)
			)
		)
		(property "Dielectric" "template_dielectric"
			(at 158.75 107.95 0)
			(effects
				(font
					(size 1.27 1.27)
				)
				(justify left bottom)
				(hide yes)
			)
		)
		(pin "1"
		)
		(pin "2"
		)
		(instances
			(project "sdi-mipi-video-converter"
				(path ""
					(reference "C88")
					(unit 1)
				)
			)
		)
	)
	(symbol
		(lib_id "antmicroCapacitorsmisc:C_100n_0201")
		(at 165.1 266.7 90)
		(unit 1)
		(exclude_from_sim no)
		(in_bom yes)
		(on_board yes)
		(dnp no)
		(fields_autoplaced yes)
		(property "Reference" "C97"
			(at 167.64 262.8835 90)
			(effects
				(font
					(size 1.27 1.27)
					(thickness 0.15)
				)
				(justify right)
			)
		)
		(property "Value" "C_100n_0201"
			(at 175.26 246.38 0)
			(effects
				(font
					(size 1.27 1.27)
					(thickness 0.15)
				)
				(justify left bottom)
				(hide yes)
			)
		)
		(property "Footprint" "antmicro-footprints:C_0201"
			(at 177.8 246.38 0)
			(effects
				(font
					(size 1.27 1.27)
					(thickness 0.15)
				)
				(justify left bottom)
				(hide yes)
			)
		)
		(property "Datasheet" "https://www.yageo.com/en/Chart/Download/pdf/CC0201KRX6S5BB104"
			(at 180.34 246.38 0)
			(effects
				(font
					(size 1.27 1.27)
					(thickness 0.15)
				)
				(justify left bottom)
				(hide yes)
			)
		)
		(property "Description" "SMD Multilayer Ceramic Capacitor, 0.1 µF, 6.3 V, 0201 [0603 Metric], ± 10%, X6S, CC Series"
			(at 165.1 266.7 0)
			(effects
				(font
					(size 1.27 1.27)
				)
				(hide yes)
			)
		)
		(property "Manufacturer" "YAGEO"
			(at 185.42 246.38 0)
			(effects
				(font
					(size 1.27 1.27)
					(thickness 0.15)
				)
				(justify left bottom)
				(hide yes)
			)
		)
		(property "MPN" "CC0201KRX6S5BB104"
			(at 182.88 246.38 0)
			(effects
				(font
					(size 1.27 1.27)
					(thickness 0.15)
				)
				(justify left bottom)
				(hide yes)
			)
		)
		(property "Val" "100n"
			(at 167.64 265.4235 90)
			(effects
				(font
					(size 1.27 1.27)
					(thickness 0.15)
				)
				(justify right)
			)
		)
		(property "License" "Apache-2.0"
			(at 187.96 246.38 0)
			(effects
				(font
					(size 1.27 1.27)
					(thickness 0.15)
				)
				(justify left bottom)
				(hide yes)
			)
		)
		(property "Author" "Antmicro"
			(at 190.5 246.38 0)
			(effects
				(font
					(size 1.27 1.27)
					(thickness 0.15)
				)
				(justify left bottom)
				(hide yes)
			)
		)
		(property "Voltage" ""
			(at 193.04 246.38 0)
			(effects
				(font
					(size 1.27 1.27)
				)
				(justify left bottom)
				(hide yes)
			)
		)
		(property "Dielectric" ""
			(at 195.58 246.38 0)
			(effects
				(font
					(size 1.27 1.27)
				)
				(justify left bottom)
				(hide yes)
			)
		)
		(property "Public" "False"
			(at 198.12 246.38 0)
			(effects
				(font
					(size 1.27 1.27)
				)
				(justify left bottom)
				(hide yes)
			)
		)
		(pin "1"
		)
		(pin "2"
		)
		(instances
			(project "sdi-mipi-video-converter"
				(path ""
					(reference "C97")
					(unit 1)
				)
			)
		)
	)
	(symbol
		(lib_id "antmicroFerriteBeadsandChips:FB_120Z_2A_Murata-BLM18PG_0603")
		(at 128.27 205.74 90)
		(unit 1)
		(exclude_from_sim no)
		(in_bom yes)
		(on_board yes)
		(dnp no)
		(fields_autoplaced yes)
		(property "Reference" "FB4"
			(at 130.81 201.968 90)
			(effects
				(font
					(size 1.27 1.27)
					(thickness 0.15)
				)
				(justify right)
			)
		)
		(property "Value" "FB_120Z_2A_0603"
			(at 133.35 190.5 0)
			(effects
				(font
					(size 1.27 1.27)
					(thickness 0.15)
				)
				(justify left bottom)
				(hide yes)
			)
		)
		(property "Footprint" "antmicro-footprints:FB_0603_1608Metric"
			(at 135.89 190.5 0)
			(effects
				(font
					(size 1.27 1.27)
					(thickness 0.15)
				)
				(justify left bottom)
				(hide yes)
			)
		)
		(property "Datasheet" "https://www.murata.com/en-us/products/productdata/8796738650142/ENFA0003.pdf"
			(at 138.43 190.5 0)
			(effects
				(font
					(size 1.27 1.27)
					(thickness 0.15)
				)
				(justify left bottom)
				(hide yes)
			)
		)
		(property "Description" "Ferrite Bead, 0603 [1608 Metric], 120 ohm, 2 A, BLM18P, 0.05 ohm, ± 25%, DC power line"
			(at 128.27 205.74 0)
			(effects
				(font
					(size 1.27 1.27)
				)
				(hide yes)
			)
		)
		(property "MPN" "BLM18PG121SN1D"
			(at 130.81 204.508 90)
			(effects
				(font
					(size 1.27 1.27)
					(thickness 0.15)
				)
				(justify right)
			)
		)
		(property "Manufacturer" "Murata"
			(at 143.51 190.5 0)
			(effects
				(font
					(size 1.27 1.27)
					(thickness 0.15)
				)
				(justify left bottom)
				(hide yes)
			)
		)
		(property "Author" "Antmicro"
			(at 146.05 190.5 0)
			(effects
				(font
					(size 1.27 1.27)
					(thickness 0.15)
				)
				(justify left bottom)
				(hide yes)
			)
		)
		(property "License" "Apache-2.0"
			(at 148.59 190.5 0)
			(effects
				(font
					(size 1.27 1.27)
					(thickness 0.15)
				)
				(justify left bottom)
				(hide yes)
			)
		)
		(property "Val" "120Z/2A"
			(at 133.35 190.5 0)
			(effects
				(font
					(size 1.27 1.27)
				)
				(justify left bottom)
			)
		)
		(property "Current" ""
			(at 151.13 185.42 0)
			(effects
				(font
					(size 1.27 1.27)
					(thickness 0.15)
				)
				(justify left bottom)
				(hide yes)
			)
		)
		(pin "1"
		)
		(pin "2"
		)
		(instances
			(project "sdi-mipi-video-converter"
				(path ""
					(reference "FB4")
					(unit 1)
				)
			)
		)
	)
)
